FILE_TYPE = MACRO_DRAWING;
SET COLOR_WIRE YELLOW;
SET COLOR_PROP ORANGE;
SET COLOR_DOT WHITE;
SET COLOR_ARC YELLOW;
SET COLOR_BODY GREEN;
SET COLOR_NOTE PURPLE;
SET PROP_DISPLAY VALUE;
SET PAGE_NUMBER P163;
FORCEADD XC7A200T_2FBG484C_FBG484..4
(-9800 8050);
FORCEPROP 1 LAST $LOCATION U24
J 0
(-9750 8150);
DISPLAY 1.212766 (-9750 8150);
PAINT GREEN (-9750 8150);
FORCEPROP 0 LAST CDS_LOCATION U24
J 0
(-9750 8450);
DISPLAY 1.021277 (-9750 8450);
DISPLAY INVISIBLE (-9750 8450);
FORCEPROP 0 LAST $SEC 4
J 0
(-9750 8450);
DISPLAY 0.680851 (-9750 8450);
PAINT MONO (-9750 8450);
DISPLAY INVISIBLE (-9750 8450);
FORCEPROP 0 LAST CDS_SEC 4
J 0
(-9750 8450);
DISPLAY 1.021277 (-9750 8450);
DISPLAY INVISIBLE (-9750 8450);
FORCEPROP 0 LASTPIN (-6700 7950) $PN T3
J 0
(-6690 7960);
DISPLAY 0.680851 (-6690 7960);
PAINT MONO (-6690 7960);
FORCEPROP 0 LASTPIN (-9900 7950) $PN F4
J 2
(-9910 7960);
DISPLAY 0.680851 (-9910 7960);
PAINT MONO (-9910 7960);
FORCEPROP 0 LASTPIN (-6700 7750) $PN U7
J 0
(-6690 7760);
DISPLAY 0.680851 (-6690 7760);
PAINT MONO (-6690 7760);
FORCEPROP 0 LASTPIN (-9900 7750) $PN L6
J 2
(-9910 7760);
DISPLAY 0.680851 (-9910 7760);
PAINT MONO (-9910 7760);
FORCEPROP 0 LASTPIN (-6700 7450) $PN U1
J 0
(-6690 7460);
DISPLAY 0.680851 (-6690 7460);
PAINT MONO (-6690 7460);
FORCEPROP 0 LASTPIN (-9900 7450) $PN A1
J 2
(-9910 7460);
DISPLAY 0.680851 (-9910 7460);
PAINT MONO (-9910 7460);
FORCEPROP 0 LASTPIN (-6700 7550) $PN T1
J 0
(-6690 7560);
DISPLAY 0.680851 (-6690 7560);
PAINT MONO (-6690 7560);
FORCEPROP 0 LASTPIN (-9900 7550) $PN B1
J 2
(-9910 7560);
DISPLAY 0.680851 (-9910 7560);
PAINT MONO (-9910 7560);
FORCEPROP 0 LASTPIN (-6700 7250) $PN V2
J 0
(-6690 7260);
DISPLAY 0.680851 (-6690 7260);
PAINT MONO (-6690 7260);
FORCEPROP 0 LASTPIN (-9900 7250) $PN B2
J 2
(-9910 7260);
DISPLAY 0.680851 (-9910 7260);
PAINT MONO (-9910 7260);
FORCEPROP 0 LASTPIN (-6700 7350) $PN U2
J 0
(-6690 7360);
DISPLAY 0.680851 (-6690 7360);
PAINT MONO (-6690 7360);
FORCEPROP 0 LASTPIN (-9900 7350) $PN C2
J 2
(-9910 7360);
DISPLAY 0.680851 (-9910 7360);
PAINT MONO (-9910 7360);
FORCEPROP 0 LASTPIN (-6700 7050) $PN R2
J 0
(-6690 7060);
DISPLAY 0.680851 (-6690 7060);
PAINT MONO (-6690 7060);
FORCEPROP 0 LASTPIN (-9900 7050) $PN D1
J 2
(-9910 7060);
DISPLAY 0.680851 (-9910 7060);
PAINT MONO (-9910 7060);
FORCEPROP 0 LASTPIN (-6700 7150) $PN R3
J 0
(-6690 7160);
DISPLAY 0.680851 (-6690 7160);
PAINT MONO (-6690 7160);
FORCEPROP 0 LASTPIN (-9900 7150) $PN E1
J 2
(-9910 7160);
DISPLAY 0.680851 (-9910 7160);
PAINT MONO (-9910 7160);
FORCEPROP 0 LASTPIN (-6700 6850) $PN Y2
J 0
(-6690 6860);
DISPLAY 0.680851 (-6690 6860);
PAINT MONO (-6690 6860);
FORCEPROP 0 LASTPIN (-9900 6850) $PN D2
J 2
(-9910 6860);
DISPLAY 0.680851 (-9910 6860);
PAINT MONO (-9910 6860);
FORCEPROP 0 LASTPIN (-6700 6950) $PN W2
J 0
(-6690 6960);
DISPLAY 0.680851 (-6690 6960);
PAINT MONO (-6690 6960);
FORCEPROP 0 LASTPIN (-9900 6950) $PN E2
J 2
(-9910 6960);
DISPLAY 0.680851 (-9910 6960);
PAINT MONO (-9910 6960);
FORCEPROP 0 LASTPIN (-6700 6650) $PN Y1
J 0
(-6690 6660);
DISPLAY 0.680851 (-6690 6660);
PAINT MONO (-6690 6660);
FORCEPROP 0 LASTPIN (-9900 6650) $PN F1
J 2
(-9910 6660);
DISPLAY 0.680851 (-9910 6660);
PAINT MONO (-9910 6660);
FORCEPROP 0 LASTPIN (-6700 6750) $PN W1
J 0
(-6690 6760);
DISPLAY 0.680851 (-6690 6760);
PAINT MONO (-6690 6760);
FORCEPROP 0 LASTPIN (-9900 6750) $PN G1
J 2
(-9910 6760);
DISPLAY 0.680851 (-9910 6760);
PAINT MONO (-9910 6760);
FORCEPROP 0 LASTPIN (-6700 6450) $PN V3
J 0
(-6690 6460);
DISPLAY 0.680851 (-6690 6460);
PAINT MONO (-6690 6460);
FORCEPROP 0 LASTPIN (-9900 6450) $PN E3
J 2
(-9910 6460);
DISPLAY 0.680851 (-9910 6460);
PAINT MONO (-9910 6460);
FORCEPROP 0 LASTPIN (-6700 6550) $PN U3
J 0
(-6690 6560);
DISPLAY 0.680851 (-6690 6560);
PAINT MONO (-6690 6560);
FORCEPROP 0 LASTPIN (-9900 6550) $PN F3
J 2
(-9910 6560);
DISPLAY 0.680851 (-9910 6560);
PAINT MONO (-9910 6560);
FORCEPROP 0 LASTPIN (-6700 6250) $PN AB1
J 0
(-6690 6260);
DISPLAY 0.680851 (-6690 6260);
PAINT MONO (-6690 6260);
FORCEPROP 0 LASTPIN (-9900 6250) $PN J1
J 2
(-9910 6260);
DISPLAY 0.680851 (-9910 6260);
PAINT MONO (-9910 6260);
FORCEPROP 0 LASTPIN (-6700 6350) $PN AA1
J 0
(-6690 6360);
DISPLAY 0.680851 (-6690 6360);
PAINT MONO (-6690 6360);
FORCEPROP 0 LASTPIN (-9900 6350) $PN K1
J 2
(-9910 6360);
DISPLAY 0.680851 (-9910 6360);
PAINT MONO (-9910 6360);
FORCEPROP 0 LASTPIN (-6700 6050) $PN AB2
J 0
(-6690 6060);
DISPLAY 0.680851 (-6690 6060);
PAINT MONO (-6690 6060);
FORCEPROP 0 LASTPIN (-9900 6050) $PN G2
J 2
(-9910 6060);
DISPLAY 0.680851 (-9910 6060);
PAINT MONO (-9910 6060);
FORCEPROP 0 LASTPIN (-6700 6150) $PN AB3
J 0
(-6690 6160);
DISPLAY 0.680851 (-6690 6160);
PAINT MONO (-6690 6160);
FORCEPROP 0 LASTPIN (-9900 6150) $PN H2
J 2
(-9910 6160);
DISPLAY 0.680851 (-9910 6160);
PAINT MONO (-9910 6160);
FORCEPROP 0 LASTPIN (-6700 5850) $PN AA3
J 0
(-6690 5860);
DISPLAY 0.680851 (-6690 5860);
PAINT MONO (-6690 5860);
FORCEPROP 0 LASTPIN (-9900 5850) $PN J2
J 2
(-9910 5860);
DISPLAY 0.680851 (-9910 5860);
PAINT MONO (-9910 5860);
FORCEPROP 0 LASTPIN (-6700 5950) $PN Y3
J 0
(-6690 5960);
DISPLAY 0.680851 (-6690 5960);
PAINT MONO (-6690 5960);
FORCEPROP 0 LASTPIN (-9900 5950) $PN K2
J 2
(-9910 5960);
DISPLAY 0.680851 (-9910 5960);
PAINT MONO (-9910 5960);
FORCEPROP 0 LASTPIN (-6700 5650) $PN AB5
J 0
(-6690 5660);
DISPLAY 0.680851 (-6690 5660);
PAINT MONO (-6690 5660);
FORCEPROP 0 LASTPIN (-9900 5650) $PN H5
J 2
(-9910 5660);
DISPLAY 0.680851 (-9910 5660);
PAINT MONO (-9910 5660);
FORCEPROP 0 LASTPIN (-6700 5750) $PN AA5
J 0
(-6690 5760);
DISPLAY 0.680851 (-6690 5760);
PAINT MONO (-6690 5760);
FORCEPROP 0 LASTPIN (-9900 5750) $PN J5
J 2
(-9910 5760);
DISPLAY 0.680851 (-9910 5760);
PAINT MONO (-9910 5760);
FORCEPROP 0 LASTPIN (-6700 5450) $PN AA4
J 0
(-6690 5460);
DISPLAY 0.680851 (-6690 5460);
PAINT MONO (-6690 5460);
FORCEPROP 0 LASTPIN (-9900 5450) $PN G3
J 2
(-9910 5460);
DISPLAY 0.680851 (-9910 5460);
PAINT MONO (-9910 5460);
FORCEPROP 0 LASTPIN (-6700 5550) $PN Y4
J 0
(-6690 5560);
DISPLAY 0.680851 (-6690 5560);
PAINT MONO (-6690 5560);
FORCEPROP 0 LASTPIN (-9900 5550) $PN H3
J 2
(-9910 5560);
DISPLAY 0.680851 (-9910 5560);
PAINT MONO (-9910 5560);
FORCEPROP 0 LASTPIN (-6700 5250) $PN W4
J 0
(-6690 5260);
DISPLAY 0.680851 (-6690 5260);
PAINT MONO (-6690 5260);
FORCEPROP 0 LASTPIN (-9900 5250) $PN G4
J 2
(-9910 5260);
DISPLAY 0.680851 (-9910 5260);
PAINT MONO (-9910 5260);
FORCEPROP 0 LASTPIN (-6700 5350) $PN V4
J 0
(-6690 5360);
DISPLAY 0.680851 (-6690 5360);
PAINT MONO (-6690 5360);
FORCEPROP 0 LASTPIN (-9900 5350) $PN H4
J 2
(-9910 5360);
DISPLAY 0.680851 (-9910 5360);
PAINT MONO (-9910 5360);
FORCEPROP 0 LASTPIN (-6700 5050) $PN T4
J 0
(-6690 5060);
DISPLAY 0.680851 (-6690 5060);
PAINT MONO (-6690 5060);
FORCEPROP 0 LASTPIN (-9900 5050) $PN J4
J 2
(-9910 5060);
DISPLAY 0.680851 (-9910 5060);
PAINT MONO (-9910 5060);
FORCEPROP 0 LASTPIN (-6700 5150) $PN R4
J 0
(-6690 5160);
DISPLAY 0.680851 (-6690 5160);
PAINT MONO (-6690 5160);
FORCEPROP 0 LASTPIN (-9900 5150) $PN K4
J 2
(-9910 5160);
DISPLAY 0.680851 (-9910 5160);
PAINT MONO (-9910 5160);
FORCEPROP 0 LASTPIN (-6700 4850) $PN U5
J 0
(-6690 4860);
DISPLAY 0.680851 (-6690 4860);
PAINT MONO (-6690 4860);
FORCEPROP 0 LASTPIN (-9900 4850) $PN K3
J 2
(-9910 4860);
DISPLAY 0.680851 (-9910 4860);
PAINT MONO (-9910 4860);
FORCEPROP 0 LASTPIN (-6700 4950) $PN T5
J 0
(-6690 4960);
DISPLAY 0.680851 (-6690 4960);
PAINT MONO (-6690 4960);
FORCEPROP 0 LASTPIN (-9900 4950) $PN L3
J 2
(-9910 4960);
DISPLAY 0.680851 (-9910 4960);
PAINT MONO (-9910 4960);
FORCEPROP 0 LASTPIN (-6700 4650) $PN W5
J 0
(-6690 4660);
DISPLAY 0.680851 (-6690 4660);
PAINT MONO (-6690 4660);
FORCEPROP 0 LASTPIN (-9900 4650) $PN L1
J 2
(-9910 4660);
DISPLAY 0.680851 (-9910 4660);
PAINT MONO (-9910 4660);
FORCEPROP 0 LASTPIN (-6700 4750) $PN W6
J 0
(-6690 4760);
DISPLAY 0.680851 (-6690 4760);
PAINT MONO (-6690 4760);
FORCEPROP 0 LASTPIN (-9900 4750) $PN M1
J 2
(-9910 4760);
DISPLAY 0.680851 (-9910 4760);
PAINT MONO (-9910 4760);
FORCEPROP 0 LASTPIN (-6700 4450) $PN V5
J 0
(-6690 4460);
DISPLAY 0.680851 (-6690 4460);
PAINT MONO (-6690 4460);
FORCEPROP 0 LASTPIN (-9900 4450) $PN M2
J 2
(-9910 4460);
DISPLAY 0.680851 (-9910 4460);
PAINT MONO (-9910 4460);
FORCEPROP 0 LASTPIN (-6700 4550) $PN U6
J 0
(-6690 4560);
DISPLAY 0.680851 (-6690 4560);
PAINT MONO (-6690 4560);
FORCEPROP 0 LASTPIN (-9900 4550) $PN M3
J 2
(-9910 4560);
DISPLAY 0.680851 (-9910 4560);
PAINT MONO (-9910 4560);
FORCEPROP 0 LASTPIN (-6700 4250) $PN T6
J 0
(-6690 4260);
DISPLAY 0.680851 (-6690 4260);
PAINT MONO (-6690 4260);
FORCEPROP 0 LASTPIN (-9900 4250) $PN J6
J 2
(-9910 4260);
DISPLAY 0.680851 (-9910 4260);
PAINT MONO (-9910 4260);
FORCEPROP 0 LASTPIN (-6700 4350) $PN R6
J 0
(-6690 4360);
DISPLAY 0.680851 (-6690 4360);
PAINT MONO (-6690 4360);
FORCEPROP 0 LASTPIN (-9900 4350) $PN K6
J 2
(-9910 4360);
DISPLAY 0.680851 (-9910 4360);
PAINT MONO (-9910 4360);
FORCEPROP 0 LASTPIN (-6700 4050) $PN AA6
J 0
(-6690 4060);
DISPLAY 0.680851 (-6690 4060);
PAINT MONO (-6690 4060);
FORCEPROP 0 LASTPIN (-9900 4050) $PN L4
J 2
(-9910 4060);
DISPLAY 0.680851 (-9910 4060);
PAINT MONO (-9910 4060);
FORCEPROP 0 LASTPIN (-6700 4150) $PN Y6
J 0
(-6690 4160);
DISPLAY 0.680851 (-6690 4160);
PAINT MONO (-6690 4160);
FORCEPROP 0 LASTPIN (-9900 4150) $PN L5
J 2
(-9910 4160);
DISPLAY 0.680851 (-9910 4160);
PAINT MONO (-9910 4160);
FORCEPROP 0 LASTPIN (-6700 3850) $PN W7
J 0
(-6690 3860);
DISPLAY 0.680851 (-6690 3860);
PAINT MONO (-6690 3860);
FORCEPROP 0 LASTPIN (-9900 3850) $PN N3
J 2
(-9910 3860);
DISPLAY 0.680851 (-9910 3860);
PAINT MONO (-9910 3860);
FORCEPROP 0 LASTPIN (-6700 3950) $PN V7
J 0
(-6690 3960);
DISPLAY 0.680851 (-6690 3960);
PAINT MONO (-6690 3960);
FORCEPROP 0 LASTPIN (-9900 3950) $PN N4
J 2
(-9910 3960);
DISPLAY 0.680851 (-9910 3960);
PAINT MONO (-9910 3960);
FORCEPROP 0 LASTPIN (-6700 3650) $PN AB6
J 0
(-6690 3660);
DISPLAY 0.680851 (-6690 3660);
PAINT MONO (-6690 3660);
FORCEPROP 0 LASTPIN (-9900 3650) $PN P1
J 2
(-9910 3660);
DISPLAY 0.680851 (-9910 3660);
PAINT MONO (-9910 3660);
FORCEPROP 0 LASTPIN (-6700 3750) $PN AB7
J 0
(-6690 3760);
DISPLAY 0.680851 (-6690 3760);
PAINT MONO (-6690 3760);
FORCEPROP 0 LASTPIN (-9900 3750) $PN R1
J 2
(-9910 3760);
DISPLAY 0.680851 (-9910 3760);
PAINT MONO (-9910 3760);
FORCEPROP 0 LASTPIN (-6700 3450) $PN V8
J 0
(-6690 3460);
DISPLAY 0.680851 (-6690 3460);
PAINT MONO (-6690 3460);
FORCEPROP 0 LASTPIN (-9900 3450) $PN P4
J 2
(-9910 3460);
DISPLAY 0.680851 (-9910 3460);
PAINT MONO (-9910 3460);
FORCEPROP 0 LASTPIN (-6700 3550) $PN V9
J 0
(-6690 3560);
DISPLAY 0.680851 (-6690 3560);
PAINT MONO (-6690 3560);
FORCEPROP 0 LASTPIN (-9900 3550) $PN P5
J 2
(-9910 3560);
DISPLAY 0.680851 (-9910 3560);
PAINT MONO (-9910 3560);
FORCEPROP 0 LASTPIN (-6700 3250) $PN AB8
J 0
(-6690 3260);
DISPLAY 0.680851 (-6690 3260);
PAINT MONO (-6690 3260);
FORCEPROP 0 LASTPIN (-9900 3250) $PN N2
J 2
(-9910 3260);
DISPLAY 0.680851 (-9910 3260);
PAINT MONO (-9910 3260);
FORCEPROP 0 LASTPIN (-6700 3350) $PN AA8
J 0
(-6690 3360);
DISPLAY 0.680851 (-6690 3360);
PAINT MONO (-6690 3360);
FORCEPROP 0 LASTPIN (-9900 3350) $PN P2
J 2
(-9910 3360);
DISPLAY 0.680851 (-9910 3360);
PAINT MONO (-9910 3360);
FORCEPROP 0 LASTPIN (-6700 3050) $PN Y7
J 0
(-6690 3060);
DISPLAY 0.680851 (-6690 3060);
PAINT MONO (-6690 3060);
FORCEPROP 0 LASTPIN (-9900 3050) $PN M5
J 2
(-9910 3060);
DISPLAY 0.680851 (-9910 3060);
PAINT MONO (-9910 3060);
FORCEPROP 0 LASTPIN (-6700 3150) $PN Y8
J 0
(-6690 3160);
DISPLAY 0.680851 (-6690 3160);
PAINT MONO (-6690 3160);
FORCEPROP 0 LASTPIN (-9900 3150) $PN M6
J 2
(-9910 3160);
DISPLAY 0.680851 (-9910 3160);
PAINT MONO (-9910 3160);
FORCEPROP 0 LASTPIN (-6700 2850) $PN Y9
J 0
(-6690 2860);
DISPLAY 0.680851 (-6690 2860);
PAINT MONO (-6690 2860);
FORCEPROP 0 LASTPIN (-9900 2850) $PN N5
J 2
(-9910 2860);
DISPLAY 0.680851 (-9910 2860);
PAINT MONO (-9910 2860);
FORCEPROP 0 LASTPIN (-6700 2950) $PN W9
J 0
(-6690 2960);
DISPLAY 0.680851 (-6690 2960);
PAINT MONO (-6690 2960);
FORCEPROP 0 LASTPIN (-9900 2950) $PN P6
J 2
(-9910 2960);
DISPLAY 0.680851 (-9910 2960);
PAINT MONO (-9910 2960);
FORCEPROP 1 LAST CLS_PN G240-10069-01
J 0
(-9750 8250);
DISPLAY 1.212766 (-9750 8250);
PAINT GREEN (-9750 8250);
FORCEPROP 2 LAST CDS_LIB pld
J 0
(-9800 8050);
DISPLAY INVISIBLE (-9800 8050);
FORCEPROP 1 LAST CDS_LMAN_SYM_OUTLINE 0,0,3000,-5400
J 0
(-9800 8050);
DISPLAY 0.468085 (-9800 8050);
PAINT GREEN (-9800 8050);
DISPLAY INVISIBLE (-9800 8050);
FORCEPROP 1 LAST PATH I1
J 0
(-9750 8100);
DISPLAY 1.212766 (-9750 8100);
PAINT GREEN (-9750 8100);
DISPLAY INVISIBLE (-9750 8100);
FORCEADD OFFPAGE_BI..1
R 6
(-5800 3150);
FORCEPROP 1 LAST BODY_TYPE COMMENT
J 0
(-5790 2977);
DISPLAY 0.808511 (-5790 2977);
PAINT GREEN (-5790 2977);
DISPLAY INVISIBLE (-5790 2977);
FORCEPROP 1 LAST CDS_LMAN_SYM_OUTLINE -50,50,50,-50
J 0
(-5800 3150);
DISPLAY 0.468085 (-5800 3150);
PAINT GREEN (-5800 3150);
DISPLAY INVISIBLE (-5800 3150);
FORCEPROP 2 LAST CDS_LIB cls
J 0
(-5800 3150);
DISPLAY INVISIBLE (-5800 3150);
FORCEPROP 1 LAST OFFPAGE TRUE
J 0
(-5790 3057);
DISPLAY 0.808511 (-5790 3057);
PAINT GREEN (-5790 3057);
DISPLAY INVISIBLE (-5790 3057);
FORCEPROP 2 LAST PATH I112
J 0
(-5700 3200);
DISPLAY 1.021277 (-5700 3200);
DISPLAY INVISIBLE (-5700 3200);
FORCEPROP 2 LAST $XR0 25E3<> 
J 0
(-5740 3150);
DISPLAY 0.638298 (-5740 3150);
PAINT MONO (-5740 3150);
FORCEADD OFFPAGE_BI..1
R 6
(-5800 3250);
FORCEPROP 2 LAST CDS_LIB cls
J 0
(-5800 3250);
DISPLAY INVISIBLE (-5800 3250);
FORCEPROP 1 LAST CDS_LMAN_SYM_OUTLINE -50,50,50,-50
J 0
(-5800 3250);
DISPLAY 0.468085 (-5800 3250);
PAINT GREEN (-5800 3250);
DISPLAY INVISIBLE (-5800 3250);
FORCEPROP 1 LAST BODY_TYPE COMMENT
J 0
(-5790 3077);
DISPLAY 0.808511 (-5790 3077);
PAINT GREEN (-5790 3077);
DISPLAY INVISIBLE (-5790 3077);
FORCEPROP 1 LAST OFFPAGE TRUE
J 0
(-5790 3157);
DISPLAY 0.808511 (-5790 3157);
PAINT GREEN (-5790 3157);
DISPLAY INVISIBLE (-5790 3157);
FORCEPROP 2 LAST PATH I113
J 0
(-5700 3300);
DISPLAY 1.021277 (-5700 3300);
DISPLAY INVISIBLE (-5700 3300);
FORCEPROP 2 LAST $XR0 25D3<> 
J 0
(-5740 3250);
DISPLAY 0.638298 (-5740 3250);
PAINT MONO (-5740 3250);
FORCEADD OFFPAGE_BI..1
R 6
(-5800 2950);
FORCEPROP 1 LAST BODY_TYPE COMMENT
J 0
(-5790 2777);
DISPLAY 0.808511 (-5790 2777);
PAINT GREEN (-5790 2777);
DISPLAY INVISIBLE (-5790 2777);
FORCEPROP 1 LAST CDS_LMAN_SYM_OUTLINE -50,50,50,-50
J 0
(-5800 2950);
DISPLAY 0.468085 (-5800 2950);
PAINT GREEN (-5800 2950);
DISPLAY INVISIBLE (-5800 2950);
FORCEPROP 2 LAST CDS_LIB cls
J 0
(-5800 2950);
DISPLAY INVISIBLE (-5800 2950);
FORCEPROP 1 LAST OFFPAGE TRUE
J 0
(-5790 2857);
DISPLAY 0.808511 (-5790 2857);
PAINT GREEN (-5790 2857);
DISPLAY INVISIBLE (-5790 2857);
FORCEPROP 2 LAST PATH I114
J 0
(-5700 3000);
DISPLAY 1.021277 (-5700 3000);
DISPLAY INVISIBLE (-5700 3000);
FORCEPROP 2 LAST $XR0 25E3<> 
J 0
(-5740 2950);
DISPLAY 0.638298 (-5740 2950);
PAINT MONO (-5740 2950);
FORCEADD OFFPAGE_BI..1
R 6
(-5800 3550);
FORCEPROP 2 LAST CDS_LIB cls
J 0
(-5800 3550);
DISPLAY INVISIBLE (-5800 3550);
FORCEPROP 1 LAST CDS_LMAN_SYM_OUTLINE -50,50,50,-50
J 0
(-5800 3550);
DISPLAY 0.468085 (-5800 3550);
PAINT GREEN (-5800 3550);
DISPLAY INVISIBLE (-5800 3550);
FORCEPROP 1 LAST BODY_TYPE COMMENT
J 0
(-5790 3377);
DISPLAY 0.808511 (-5790 3377);
PAINT GREEN (-5790 3377);
DISPLAY INVISIBLE (-5790 3377);
FORCEPROP 1 LAST OFFPAGE TRUE
J 0
(-5790 3457);
DISPLAY 0.808511 (-5790 3457);
PAINT GREEN (-5790 3457);
DISPLAY INVISIBLE (-5790 3457);
FORCEPROP 2 LAST PATH I115
J 0
(-5700 3600);
DISPLAY 1.021277 (-5700 3600);
DISPLAY INVISIBLE (-5700 3600);
FORCEPROP 2 LAST $XR0 25D3<> 
J 0
(-5740 3550);
DISPLAY 0.638298 (-5740 3550);
PAINT MONO (-5740 3550);
FORCEADD RESISTOR..2
R 1
(-3850 5350);
FORCEPROP 1 LAST $LOCATION R355
J 0
(-4250 5350);
DISPLAY 1.212766 (-4250 5350);
PAINT GREEN (-4250 5350);
FORCEPROP 0 LAST CDS_LOCATION R355
R 1
J 0
(-3650 5450);
DISPLAY 1.021277 (-3650 5450);
DISPLAY INVISIBLE (-3650 5450);
FORCEPROP 0 LAST $SEC 1
R 1
J 0
(-3650 5450);
DISPLAY 0.680851 (-3650 5450);
PAINT MONO (-3650 5450);
DISPLAY INVISIBLE (-3650 5450);
FORCEPROP 0 LAST CDS_SEC 1
R 1
J 0
(-3650 5450);
DISPLAY 1.021277 (-3650 5450);
DISPLAY INVISIBLE (-3650 5450);
FORCEPROP 0 LASTPIN (-3950 5350) $PN 1
J 2
(-3960 5360);
DISPLAY 0.680851 (-3960 5360);
PAINT MONO (-3960 5360);
FORCEPROP 0 LASTPIN (-3700 5350) $PN 2
J 0
(-3690 5360);
DISPLAY 0.680851 (-3690 5360);
PAINT MONO (-3690 5360);
FORCEPROP 0 LAST PACKAGE 0402
J 0
(-3900 5400);
DISPLAY 1.021277 (-3900 5400);
FORCEPROP 1 LAST VALUE 10KOHM
J 0
(-3650 5350);
DISPLAY 1.212766 (-3650 5350);
PAINT GREEN (-3650 5350);
FORCEPROP 1 LAST CDS_LMAN_SYM_OUTLINE -50,50,50,-100
R 1
J 0
(-3850 5350);
DISPLAY 0.468085 (-3850 5350);
PAINT GREEN (-3850 5350);
DISPLAY INVISIBLE (-3850 5350);
FORCEPROP 2 LAST CDS_LIB passive
J 0
(-3850 5350);
DISPLAY INVISIBLE (-3850 5350);
FORCEPROP 1 LAST CLS_PN G155-11002-01
R 1
J 0
(-4050 5214);
DISPLAY 1.212766 (-4050 5214);
PAINT GREEN (-4050 5214);
DISPLAY INVISIBLE (-4050 5214);
FORCEPROP 1 LAST TOLERANCE 1%
R 1
J 0
(-4105 5153);
DISPLAY 1.212766 (-4105 5153);
PAINT GREEN (-4105 5153);
DISPLAY INVISIBLE (-4105 5153);
FORCEPROP 1 LAST PATH I120
R 1
J 0
(-3955 5153);
DISPLAY 1.212766 (-3955 5153);
PAINT GREEN (-3955 5153);
DISPLAY INVISIBLE (-3955 5153);
FORCEADD GND_SG..1
(-3100 4700);
FORCEPROP 3 LASTPIN (-3050 4750) SIG_NAME SG\g
J 0
(-3040 4760);
DISPLAY 0.659574 (-3040 4760);
PAINT MONO (-3040 4760);
DISPLAY INVISIBLE (-3040 4760);
FORCEPROP 1 LAST HDL_POWER SG
J 1
(-3045 4605);
DISPLAY 0.808511 (-3045 4605);
PAINT GREEN (-3045 4605);
FORCEPROP 1 LAST CDS_LMAN_SYM_OUTLINE 0,0,100,-50
J 0
(-3100 4700);
DISPLAY 0.468085 (-3100 4700);
PAINT GREEN (-3100 4700);
DISPLAY INVISIBLE (-3100 4700);
FORCEPROP 2 LAST CDS_LIB cls
J 0
(-3100 4700);
DISPLAY INVISIBLE (-3100 4700);
FORCEPROP 1 LAST BODY_TYPE PLUMBING
J 0
(-3085 4685);
DISPLAY 0.808511 (-3085 4685);
PAINT GREEN (-3085 4685);
DISPLAY INVISIBLE (-3085 4685);
FORCEPROP 1 LAST PATH I124
J 0
(-3065 4700);
DISPLAY 0.808511 (-3065 4700);
PAINT GREEN (-3065 4700);
DISPLAY INVISIBLE (-3065 4700);
FORCEADD VCC..1
(-3000 5400);
FORCEPROP 3 LASTPIN (-2950 5350) SIG_NAME XP2R5V_FPGA\g
J 0
(-2940 5360);
DISPLAY 0.659574 (-2940 5360);
PAINT MONO (-2940 5360);
DISPLAY INVISIBLE (-2940 5360);
FORCEPROP 0 LAST VOLTAGE 2.5V
J 0
(-3250 5550);
DISPLAY 1.021277 (-3250 5550);
DISPLAY BOTH (-3250 5550);
FORCEPROP 1 LAST HDL_POWER XP2R5V_FPGA
J 1
(-2950 5450);
DISPLAY 1.021277 (-2950 5450);
PAINT GREEN (-2950 5450);
FORCEPROP 2 LAST CDS_LIB cls
J 0
(-3000 5400);
DISPLAY INVISIBLE (-3000 5400);
FORCEPROP 1 LAST CDS_LMAN_SYM_OUTLINE -250,250,250,-250
J 0
(-3000 5400);
DISPLAY 0.468085 (-3000 5400);
PAINT GREEN (-3000 5400);
DISPLAY INVISIBLE (-3000 5400);
FORCEPROP 1 LAST BODY_TYPE PLUMBING
J 0
(-3045 5357);
DISPLAY 0.340426 (-3045 5357);
PAINT GREEN (-3045 5357);
DISPLAY INVISIBLE (-3045 5357);
FORCEPROP 1 LAST PATH I125
J 0
(-2965 5490);
DISPLAY 0.808511 (-2965 5490);
PAINT GREEN (-2965 5490);
DISPLAY INVISIBLE (-2965 5490);
FORCEADD RESISTOR..2
R 1
(-3850 5250);
FORCEPROP 1 LAST LOCATION R358
J 0
(-4250 5250);
DISPLAY 1.212766 (-4250 5250);
PAINT GREEN (-4250 5250);
FORCEPROP 0 LAST $SEC 1
R 1
J 0
(-3650 5350);
DISPLAY 0.680851 (-3650 5350);
PAINT MONO (-3650 5350);
DISPLAY INVISIBLE (-3650 5350);
FORCEPROP 0 LAST CDS_SEC 1
R 1
J 0
(-3650 5350);
DISPLAY 1.021277 (-3650 5350);
DISPLAY INVISIBLE (-3650 5350);
FORCEPROP 0 LASTPIN (-3950 5250) $PN 1
J 2
(-3960 5260);
DISPLAY 0.680851 (-3960 5260);
PAINT MONO (-3960 5260);
FORCEPROP 0 LASTPIN (-3700 5250) $PN 2
J 0
(-3690 5260);
DISPLAY 0.680851 (-3690 5260);
PAINT MONO (-3690 5260);
FORCEPROP 0 LAST PACKAGE 0402
J 0
(-3900 5150);
DISPLAY 1.021277 (-3900 5150);
FORCEPROP 1 LAST VALUE 10KOHM
J 0
(-3650 5250);
DISPLAY 1.212766 (-3650 5250);
PAINT GREEN (-3650 5250);
FORCEPROP 1 LAST CDS_LMAN_SYM_OUTLINE -50,50,50,-100
R 1
J 0
(-3850 5250);
DISPLAY 0.468085 (-3850 5250);
PAINT GREEN (-3850 5250);
DISPLAY INVISIBLE (-3850 5250);
FORCEPROP 2 LAST CDS_LIB passive
J 0
(-3850 5250);
DISPLAY INVISIBLE (-3850 5250);
FORCEPROP 1 LAST CLS_PN G155-11002-01
R 1
J 0
(-4050 5114);
DISPLAY 1.212766 (-4050 5114);
PAINT GREEN (-4050 5114);
DISPLAY INVISIBLE (-4050 5114);
FORCEPROP 1 LAST TOLERANCE 1%
R 1
J 0
(-4105 5053);
DISPLAY 1.212766 (-4105 5053);
PAINT GREEN (-4105 5053);
DISPLAY INVISIBLE (-4105 5053);
FORCEPROP 1 LAST PATH I126
R 1
J 0
(-3955 5053);
DISPLAY 1.212766 (-3955 5053);
PAINT GREEN (-3955 5053);
DISPLAY INVISIBLE (-3955 5053);
FORCEADD RESISTOR..2
R 1
(-3850 4950);
FORCEPROP 1 LAST LOCATION R359
J 0
(-4200 4950);
DISPLAY 1.212766 (-4200 4950);
PAINT GREEN (-4200 4950);
FORCEPROP 0 LAST $SEC 1
R 1
J 0
(-3650 5050);
DISPLAY 0.680851 (-3650 5050);
PAINT MONO (-3650 5050);
DISPLAY INVISIBLE (-3650 5050);
FORCEPROP 0 LAST CDS_SEC 1
R 1
J 0
(-3650 5050);
DISPLAY 1.021277 (-3650 5050);
DISPLAY INVISIBLE (-3650 5050);
FORCEPROP 0 LASTPIN (-3950 4950) $PN 1
J 2
(-3960 4960);
DISPLAY 0.680851 (-3960 4960);
PAINT MONO (-3960 4960);
FORCEPROP 0 LASTPIN (-3700 4950) $PN 2
J 0
(-3690 4960);
DISPLAY 0.680851 (-3690 4960);
PAINT MONO (-3690 4960);
FORCEPROP 1 LAST VALUE 10KOHM
J 0
(-3650 4950);
DISPLAY 1.212766 (-3650 4950);
PAINT GREEN (-3650 4950);
FORCEPROP 0 LAST PACKAGE 0402
J 0
(-3900 5000);
DISPLAY 1.021277 (-3900 5000);
FORCEPROP 1 LAST CDS_LMAN_SYM_OUTLINE -50,50,50,-100
R 1
J 0
(-3850 4950);
DISPLAY 0.468085 (-3850 4950);
PAINT GREEN (-3850 4950);
DISPLAY INVISIBLE (-3850 4950);
FORCEPROP 2 LAST CDS_LIB passive
J 0
(-3850 4950);
DISPLAY INVISIBLE (-3850 4950);
FORCEPROP 1 LAST CLS_PN G155-11002-01
R 1
J 0
(-4050 4814);
DISPLAY 1.212766 (-4050 4814);
PAINT GREEN (-4050 4814);
DISPLAY INVISIBLE (-4050 4814);
FORCEPROP 1 LAST TOLERANCE 1%
R 1
J 0
(-4105 4753);
DISPLAY 1.212766 (-4105 4753);
PAINT GREEN (-4105 4753);
DISPLAY INVISIBLE (-4105 4753);
FORCEPROP 1 LAST PATH I127
R 1
J 0
(-3955 4753);
DISPLAY 1.212766 (-3955 4753);
PAINT GREEN (-3955 4753);
DISPLAY INVISIBLE (-3955 4753);
FORCEADD RESISTOR..2
R 1
(-3850 4850);
FORCEPROP 1 LAST LOCATION R360
J 0
(-4200 4850);
DISPLAY 1.212766 (-4200 4850);
PAINT GREEN (-4200 4850);
FORCEPROP 0 LAST $SEC 1
R 1
J 0
(-3650 4950);
DISPLAY 0.680851 (-3650 4950);
PAINT MONO (-3650 4950);
DISPLAY INVISIBLE (-3650 4950);
FORCEPROP 0 LAST CDS_SEC 1
R 1
J 0
(-3650 4950);
DISPLAY 1.021277 (-3650 4950);
DISPLAY INVISIBLE (-3650 4950);
FORCEPROP 0 LASTPIN (-3950 4850) $PN 1
J 2
(-3960 4860);
DISPLAY 0.680851 (-3960 4860);
PAINT MONO (-3960 4860);
FORCEPROP 0 LASTPIN (-3700 4850) $PN 2
J 0
(-3690 4860);
DISPLAY 0.680851 (-3690 4860);
PAINT MONO (-3690 4860);
FORCEPROP 0 LAST PACKAGE 0402
J 0
(-3900 4750);
DISPLAY 1.021277 (-3900 4750);
FORCEPROP 1 LAST VALUE 10KOHM
J 0
(-3650 4850);
DISPLAY 1.212766 (-3650 4850);
PAINT GREEN (-3650 4850);
FORCEPROP 1 LAST CDS_LMAN_SYM_OUTLINE -50,50,50,-100
R 1
J 0
(-3850 4850);
DISPLAY 0.468085 (-3850 4850);
PAINT GREEN (-3850 4850);
DISPLAY INVISIBLE (-3850 4850);
FORCEPROP 2 LAST CDS_LIB passive
J 0
(-3850 4850);
DISPLAY INVISIBLE (-3850 4850);
FORCEPROP 1 LAST CLS_PN G155-11002-01
R 1
J 0
(-4050 4714);
DISPLAY 1.212766 (-4050 4714);
PAINT GREEN (-4050 4714);
DISPLAY INVISIBLE (-4050 4714);
FORCEPROP 1 LAST TOLERANCE 1%
R 1
J 0
(-4105 4653);
DISPLAY 1.212766 (-4105 4653);
PAINT GREEN (-4105 4653);
DISPLAY INVISIBLE (-4105 4653);
FORCEPROP 1 LAST PATH I128
R 1
J 0
(-3955 4653);
DISPLAY 1.212766 (-3955 4653);
PAINT GREEN (-3955 4653);
DISPLAY INVISIBLE (-3955 4653);
FORCEADD VCC..1
(-3000 7000);
FORCEPROP 3 LASTPIN (-2950 6950) SIG_NAME XP2R5V_FPGA\g
J 0
(-2940 6960);
DISPLAY 0.659574 (-2940 6960);
PAINT MONO (-2940 6960);
DISPLAY INVISIBLE (-2940 6960);
FORCEPROP 1 LAST HDL_POWER XP2R5V_FPGA
J 1
(-2950 7050);
DISPLAY 1.021277 (-2950 7050);
PAINT GREEN (-2950 7050);
FORCEPROP 0 LAST VOLTAGE 2.5V
J 0
(-3250 7150);
DISPLAY 1.021277 (-3250 7150);
DISPLAY BOTH (-3250 7150);
FORCEPROP 1 LAST BODY_TYPE PLUMBING
J 0
(-3045 6957);
DISPLAY 0.340426 (-3045 6957);
PAINT GREEN (-3045 6957);
DISPLAY INVISIBLE (-3045 6957);
FORCEPROP 1 LAST CDS_LMAN_SYM_OUTLINE -250,250,250,-250
J 0
(-3000 7000);
DISPLAY 0.468085 (-3000 7000);
PAINT GREEN (-3000 7000);
DISPLAY INVISIBLE (-3000 7000);
FORCEPROP 1 LAST PATH I130
J 0
(-2965 7090);
DISPLAY 0.808511 (-2965 7090);
PAINT GREEN (-2965 7090);
DISPLAY INVISIBLE (-2965 7090);
FORCEPROP 2 LAST CDS_LIB cls
J 0
(-3000 7000);
DISPLAY INVISIBLE (-3000 7000);
FORCEADD GND_SG..1
(-3100 6300);
FORCEPROP 3 LASTPIN (-3050 6350) SIG_NAME SG\g
J 0
(-3040 6360);
DISPLAY 0.659574 (-3040 6360);
PAINT MONO (-3040 6360);
DISPLAY INVISIBLE (-3040 6360);
FORCEPROP 1 LAST HDL_POWER SG
J 1
(-3045 6205);
DISPLAY 0.808511 (-3045 6205);
PAINT GREEN (-3045 6205);
FORCEPROP 1 LAST BODY_TYPE PLUMBING
J 0
(-3085 6285);
DISPLAY 0.808511 (-3085 6285);
PAINT GREEN (-3085 6285);
DISPLAY INVISIBLE (-3085 6285);
FORCEPROP 1 LAST CDS_LMAN_SYM_OUTLINE 0,0,100,-50
J 0
(-3100 6300);
DISPLAY 0.468085 (-3100 6300);
PAINT GREEN (-3100 6300);
DISPLAY INVISIBLE (-3100 6300);
FORCEPROP 1 LAST PATH I131
J 0
(-3065 6300);
DISPLAY 0.808511 (-3065 6300);
PAINT GREEN (-3065 6300);
DISPLAY INVISIBLE (-3065 6300);
FORCEPROP 2 LAST CDS_LIB cls
J 0
(-3100 6300);
DISPLAY INVISIBLE (-3100 6300);
FORCEADD RESISTOR..2
R 1
(-3850 6950);
FORCEPROP 1 LAST $LOCATION R438
J 0
(-4250 6950);
DISPLAY 1.212766 (-4250 6950);
PAINT GREEN (-4250 6950);
FORCEPROP 0 LAST CDS_LOCATION R438
R 1
J 0
(-3650 7050);
DISPLAY 1.021277 (-3650 7050);
DISPLAY INVISIBLE (-3650 7050);
FORCEPROP 0 LAST $SEC 1
R 1
J 0
(-3650 7050);
DISPLAY 0.680851 (-3650 7050);
PAINT MONO (-3650 7050);
DISPLAY INVISIBLE (-3650 7050);
FORCEPROP 0 LAST CDS_SEC 1
R 1
J 0
(-3650 7050);
DISPLAY 1.021277 (-3650 7050);
DISPLAY INVISIBLE (-3650 7050);
FORCEPROP 0 LASTPIN (-3950 6950) $PN 1
J 2
(-3960 6960);
DISPLAY 0.680851 (-3960 6960);
PAINT MONO (-3960 6960);
FORCEPROP 0 LASTPIN (-3700 6950) $PN 2
J 0
(-3690 6960);
DISPLAY 0.680851 (-3690 6960);
PAINT MONO (-3690 6960);
FORCEPROP 1 LAST VALUE 10KOHM
J 0
(-3650 6950);
DISPLAY 1.212766 (-3650 6950);
PAINT GREEN (-3650 6950);
FORCEPROP 0 LAST PACKAGE 0402
J 0
(-3900 7000);
DISPLAY 1.021277 (-3900 7000);
FORCEPROP 1 LAST TOLERANCE 1%
R 1
J 0
(-4105 6753);
DISPLAY 1.212766 (-4105 6753);
PAINT GREEN (-4105 6753);
DISPLAY INVISIBLE (-4105 6753);
FORCEPROP 1 LAST CLS_PN G155-11002-01
R 1
J 0
(-4050 6814);
DISPLAY 1.212766 (-4050 6814);
PAINT GREEN (-4050 6814);
DISPLAY INVISIBLE (-4050 6814);
FORCEPROP 1 LAST CDS_LMAN_SYM_OUTLINE -50,50,50,-100
R 1
J 0
(-3850 6950);
DISPLAY 0.468085 (-3850 6950);
PAINT GREEN (-3850 6950);
DISPLAY INVISIBLE (-3850 6950);
FORCEPROP 1 LAST PATH I132
R 1
J 0
(-3955 6753);
DISPLAY 1.212766 (-3955 6753);
PAINT GREEN (-3955 6753);
DISPLAY INVISIBLE (-3955 6753);
FORCEPROP 2 LAST CDS_LIB passive
J 0
(-3850 6950);
DISPLAY INVISIBLE (-3850 6950);
FORCEADD RESISTOR..2
R 1
(-3850 6850);
FORCEPROP 1 LAST $LOCATION R439
J 0
(-4250 6850);
DISPLAY 1.212766 (-4250 6850);
PAINT GREEN (-4250 6850);
FORCEPROP 0 LAST CDS_LOCATION R439
R 1
J 0
(-3650 6950);
DISPLAY 1.021277 (-3650 6950);
DISPLAY INVISIBLE (-3650 6950);
FORCEPROP 0 LAST $SEC 1
R 1
J 0
(-3650 6950);
DISPLAY 0.680851 (-3650 6950);
PAINT MONO (-3650 6950);
DISPLAY INVISIBLE (-3650 6950);
FORCEPROP 0 LAST CDS_SEC 1
R 1
J 0
(-3650 6950);
DISPLAY 1.021277 (-3650 6950);
DISPLAY INVISIBLE (-3650 6950);
FORCEPROP 0 LASTPIN (-3950 6850) $PN 1
J 2
(-3960 6860);
DISPLAY 0.680851 (-3960 6860);
PAINT MONO (-3960 6860);
FORCEPROP 0 LASTPIN (-3700 6850) $PN 2
J 0
(-3690 6860);
DISPLAY 0.680851 (-3690 6860);
PAINT MONO (-3690 6860);
FORCEPROP 1 LAST VALUE 10KOHM
J 0
(-3650 6850);
DISPLAY 1.212766 (-3650 6850);
PAINT GREEN (-3650 6850);
FORCEPROP 0 LAST PACKAGE 0402
J 0
(-3900 6750);
DISPLAY 1.021277 (-3900 6750);
FORCEPROP 1 LAST TOLERANCE 1%
R 1
J 0
(-4105 6653);
DISPLAY 1.212766 (-4105 6653);
PAINT GREEN (-4105 6653);
DISPLAY INVISIBLE (-4105 6653);
FORCEPROP 1 LAST CLS_PN G155-11002-01
R 1
J 0
(-4050 6714);
DISPLAY 1.212766 (-4050 6714);
PAINT GREEN (-4050 6714);
DISPLAY INVISIBLE (-4050 6714);
FORCEPROP 1 LAST CDS_LMAN_SYM_OUTLINE -50,50,50,-100
R 1
J 0
(-3850 6850);
DISPLAY 0.468085 (-3850 6850);
PAINT GREEN (-3850 6850);
DISPLAY INVISIBLE (-3850 6850);
FORCEPROP 2 LAST CDS_LIB passive
J 0
(-3850 6850);
DISPLAY INVISIBLE (-3850 6850);
FORCEPROP 1 LAST PATH I133
R 1
J 0
(-3955 6653);
DISPLAY 1.212766 (-3955 6653);
PAINT GREEN (-3955 6653);
DISPLAY INVISIBLE (-3955 6653);
FORCEADD RESISTOR..2
R 1
(-3850 6450);
FORCEPROP 1 LAST $LOCATION R441
J 0
(-4250 6450);
DISPLAY 1.212766 (-4250 6450);
PAINT GREEN (-4250 6450);
FORCEPROP 0 LAST CDS_LOCATION R441
R 1
J 0
(-3650 6550);
DISPLAY 1.021277 (-3650 6550);
DISPLAY INVISIBLE (-3650 6550);
FORCEPROP 0 LAST $SEC 1
R 1
J 0
(-3650 6550);
DISPLAY 0.680851 (-3650 6550);
PAINT MONO (-3650 6550);
DISPLAY INVISIBLE (-3650 6550);
FORCEPROP 0 LAST CDS_SEC 1
R 1
J 0
(-3650 6550);
DISPLAY 1.021277 (-3650 6550);
DISPLAY INVISIBLE (-3650 6550);
FORCEPROP 0 LASTPIN (-3950 6450) $PN 1
J 2
(-3960 6460);
DISPLAY 0.680851 (-3960 6460);
PAINT MONO (-3960 6460);
FORCEPROP 0 LASTPIN (-3700 6450) $PN 2
J 0
(-3690 6460);
DISPLAY 0.680851 (-3690 6460);
PAINT MONO (-3690 6460);
FORCEPROP 1 LAST VALUE 10KOHM
J 0
(-3650 6450);
DISPLAY 1.212766 (-3650 6450);
PAINT GREEN (-3650 6450);
FORCEPROP 0 LAST PACKAGE 0402
J 0
(-3900 6350);
DISPLAY 1.021277 (-3900 6350);
FORCEPROP 1 LAST TOLERANCE 1%
R 1
J 0
(-4105 6253);
DISPLAY 1.212766 (-4105 6253);
PAINT GREEN (-4105 6253);
DISPLAY INVISIBLE (-4105 6253);
FORCEPROP 1 LAST CLS_PN G155-11002-01
R 1
J 0
(-4050 6314);
DISPLAY 1.212766 (-4050 6314);
PAINT GREEN (-4050 6314);
DISPLAY INVISIBLE (-4050 6314);
FORCEPROP 1 LAST CDS_LMAN_SYM_OUTLINE -50,50,50,-100
R 1
J 0
(-3850 6450);
DISPLAY 0.468085 (-3850 6450);
PAINT GREEN (-3850 6450);
DISPLAY INVISIBLE (-3850 6450);
FORCEPROP 2 LAST CDS_LIB passive
J 0
(-3850 6450);
DISPLAY INVISIBLE (-3850 6450);
FORCEPROP 1 LAST PATH I134
R 1
J 0
(-3955 6253);
DISPLAY 1.212766 (-3955 6253);
PAINT GREEN (-3955 6253);
DISPLAY INVISIBLE (-3955 6253);
FORCEADD RESISTOR..2
R 1
(-3850 6550);
FORCEPROP 1 LAST $LOCATION R440
J 0
(-4250 6550);
DISPLAY 1.212766 (-4250 6550);
PAINT GREEN (-4250 6550);
FORCEPROP 0 LAST CDS_LOCATION R440
R 1
J 0
(-3650 6650);
DISPLAY 1.021277 (-3650 6650);
DISPLAY INVISIBLE (-3650 6650);
FORCEPROP 0 LAST $SEC 1
R 1
J 0
(-3650 6650);
DISPLAY 0.680851 (-3650 6650);
PAINT MONO (-3650 6650);
DISPLAY INVISIBLE (-3650 6650);
FORCEPROP 0 LAST CDS_SEC 1
R 1
J 0
(-3650 6650);
DISPLAY 1.021277 (-3650 6650);
DISPLAY INVISIBLE (-3650 6650);
FORCEPROP 0 LASTPIN (-3950 6550) $PN 1
J 2
(-3960 6560);
DISPLAY 0.680851 (-3960 6560);
PAINT MONO (-3960 6560);
FORCEPROP 0 LASTPIN (-3700 6550) $PN 2
J 0
(-3690 6560);
DISPLAY 0.680851 (-3690 6560);
PAINT MONO (-3690 6560);
FORCEPROP 1 LAST VALUE 10KOHM
J 0
(-3650 6550);
DISPLAY 1.212766 (-3650 6550);
PAINT GREEN (-3650 6550);
FORCEPROP 0 LAST PACKAGE 0402
J 0
(-3900 6600);
DISPLAY 1.021277 (-3900 6600);
FORCEPROP 1 LAST TOLERANCE 1%
R 1
J 0
(-4105 6353);
DISPLAY 1.212766 (-4105 6353);
PAINT GREEN (-4105 6353);
DISPLAY INVISIBLE (-4105 6353);
FORCEPROP 1 LAST CLS_PN G155-11002-01
R 1
J 0
(-4050 6414);
DISPLAY 1.212766 (-4050 6414);
PAINT GREEN (-4050 6414);
DISPLAY INVISIBLE (-4050 6414);
FORCEPROP 1 LAST CDS_LMAN_SYM_OUTLINE -50,50,50,-100
R 1
J 0
(-3850 6550);
DISPLAY 0.468085 (-3850 6550);
PAINT GREEN (-3850 6550);
DISPLAY INVISIBLE (-3850 6550);
FORCEPROP 2 LAST CDS_LIB passive
J 0
(-3850 6550);
DISPLAY INVISIBLE (-3850 6550);
FORCEPROP 1 LAST PATH I135
R 1
J 0
(-3955 6353);
DISPLAY 1.212766 (-3955 6353);
PAINT GREEN (-3955 6353);
DISPLAY INVISIBLE (-3955 6353);
FORCEADD OFFPAGE_BI..1
R 6
(-5800 3750);
FORCEPROP 1 LAST BODY_TYPE COMMENT
J 0
(-5790 3577);
DISPLAY 0.808511 (-5790 3577);
PAINT GREEN (-5790 3577);
DISPLAY INVISIBLE (-5790 3577);
FORCEPROP 1 LAST CDS_LMAN_SYM_OUTLINE -50,50,50,-50
J 0
(-5800 3750);
DISPLAY 0.468085 (-5800 3750);
PAINT GREEN (-5800 3750);
DISPLAY INVISIBLE (-5800 3750);
FORCEPROP 2 LAST CDS_LIB cls
J 0
(-5800 3750);
DISPLAY INVISIBLE (-5800 3750);
FORCEPROP 1 LAST OFFPAGE TRUE
J 0
(-5790 3657);
DISPLAY 0.808511 (-5790 3657);
PAINT GREEN (-5790 3657);
DISPLAY INVISIBLE (-5790 3657);
FORCEPROP 2 LAST PATH I14
J 0
(-5750 3850);
DISPLAY 1.021277 (-5750 3850);
DISPLAY INVISIBLE (-5750 3850);
FORCEPROP 2 LAST $XR0 25D3<> 
J 0
(-5740 3750);
DISPLAY 0.638298 (-5740 3750);
PAINT MONO (-5740 3750);
FORCEADD OFFPAGE_BI..1
R 6
(-5800 3650);
FORCEPROP 1 LAST BODY_TYPE COMMENT
J 0
(-5790 3477);
DISPLAY 0.808511 (-5790 3477);
PAINT GREEN (-5790 3477);
DISPLAY INVISIBLE (-5790 3477);
FORCEPROP 1 LAST CDS_LMAN_SYM_OUTLINE -50,50,50,-50
J 0
(-5800 3650);
DISPLAY 0.468085 (-5800 3650);
PAINT GREEN (-5800 3650);
DISPLAY INVISIBLE (-5800 3650);
FORCEPROP 2 LAST CDS_LIB cls
J 0
(-5800 3650);
DISPLAY INVISIBLE (-5800 3650);
FORCEPROP 1 LAST OFFPAGE TRUE
J 0
(-5790 3557);
DISPLAY 0.808511 (-5790 3557);
PAINT GREEN (-5790 3557);
DISPLAY INVISIBLE (-5790 3557);
FORCEPROP 2 LAST PATH I15
J 0
(-5750 3750);
DISPLAY 1.021277 (-5750 3750);
DISPLAY INVISIBLE (-5750 3750);
FORCEPROP 2 LAST $XR0 25D3<> 
J 0
(-5740 3650);
DISPLAY 0.638298 (-5740 3650);
PAINT MONO (-5740 3650);
FORCEADD OFFPAGE_BI..1
R 6
(-5800 3450);
FORCEPROP 1 LAST BODY_TYPE COMMENT
J 0
(-5790 3277);
DISPLAY 0.808511 (-5790 3277);
PAINT GREEN (-5790 3277);
DISPLAY INVISIBLE (-5790 3277);
FORCEPROP 1 LAST CDS_LMAN_SYM_OUTLINE -50,50,50,-50
J 0
(-5800 3450);
DISPLAY 0.468085 (-5800 3450);
PAINT GREEN (-5800 3450);
DISPLAY INVISIBLE (-5800 3450);
FORCEPROP 2 LAST CDS_LIB cls
J 0
(-5800 3450);
DISPLAY INVISIBLE (-5800 3450);
FORCEPROP 1 LAST OFFPAGE TRUE
J 0
(-5790 3357);
DISPLAY 0.808511 (-5790 3357);
PAINT GREEN (-5790 3357);
DISPLAY INVISIBLE (-5790 3357);
FORCEPROP 2 LAST PATH I16
J 0
(-5750 3550);
DISPLAY 1.021277 (-5750 3550);
DISPLAY INVISIBLE (-5750 3550);
FORCEPROP 2 LAST $XR0 25D3<> 
J 0
(-5740 3450);
DISPLAY 0.638298 (-5740 3450);
PAINT MONO (-5740 3450);
FORCEADD OFFPAGE_BI..1
R 6
(-5800 3350);
FORCEPROP 1 LAST BODY_TYPE COMMENT
J 0
(-5790 3177);
DISPLAY 0.808511 (-5790 3177);
PAINT GREEN (-5790 3177);
DISPLAY INVISIBLE (-5790 3177);
FORCEPROP 1 LAST CDS_LMAN_SYM_OUTLINE -50,50,50,-50
J 0
(-5800 3350);
DISPLAY 0.468085 (-5800 3350);
PAINT GREEN (-5800 3350);
DISPLAY INVISIBLE (-5800 3350);
FORCEPROP 2 LAST CDS_LIB cls
J 0
(-5800 3350);
DISPLAY INVISIBLE (-5800 3350);
FORCEPROP 1 LAST OFFPAGE TRUE
J 0
(-5790 3257);
DISPLAY 0.808511 (-5790 3257);
PAINT GREEN (-5790 3257);
DISPLAY INVISIBLE (-5790 3257);
FORCEPROP 2 LAST PATH I17
J 0
(-5750 3450);
DISPLAY 1.021277 (-5750 3450);
DISPLAY INVISIBLE (-5750 3450);
FORCEPROP 2 LAST $XR0 25D3<> 
J 0
(-5740 3350);
DISPLAY 0.638298 (-5740 3350);
PAINT MONO (-5740 3350);
FORCEADD OFFPAGE_BI..1
R 6
(-5800 3050);
FORCEPROP 1 LAST BODY_TYPE COMMENT
J 0
(-5790 2877);
DISPLAY 0.808511 (-5790 2877);
PAINT GREEN (-5790 2877);
DISPLAY INVISIBLE (-5790 2877);
FORCEPROP 1 LAST CDS_LMAN_SYM_OUTLINE -50,50,50,-50
J 0
(-5800 3050);
DISPLAY 0.468085 (-5800 3050);
PAINT GREEN (-5800 3050);
DISPLAY INVISIBLE (-5800 3050);
FORCEPROP 2 LAST CDS_LIB cls
J 0
(-5800 3050);
DISPLAY INVISIBLE (-5800 3050);
FORCEPROP 1 LAST OFFPAGE TRUE
J 0
(-5790 2957);
DISPLAY 0.808511 (-5790 2957);
PAINT GREEN (-5790 2957);
DISPLAY INVISIBLE (-5790 2957);
FORCEPROP 2 LAST PATH I18
J 0
(-5750 3150);
DISPLAY 1.021277 (-5750 3150);
DISPLAY INVISIBLE (-5750 3150);
FORCEPROP 2 LAST $XR0 25E3<> 
J 0
(-5740 3050);
DISPLAY 0.638298 (-5740 3050);
PAINT MONO (-5740 3050);
FORCEADD OFFPAGE_BI..1
R 6
(-5800 2850);
FORCEPROP 1 LAST BODY_TYPE COMMENT
J 0
(-5790 2677);
DISPLAY 0.808511 (-5790 2677);
PAINT GREEN (-5790 2677);
DISPLAY INVISIBLE (-5790 2677);
FORCEPROP 1 LAST CDS_LMAN_SYM_OUTLINE -50,50,50,-50
J 0
(-5800 2850);
DISPLAY 0.468085 (-5800 2850);
PAINT GREEN (-5800 2850);
DISPLAY INVISIBLE (-5800 2850);
FORCEPROP 2 LAST CDS_LIB cls
J 0
(-5800 2850);
DISPLAY INVISIBLE (-5800 2850);
FORCEPROP 1 LAST OFFPAGE TRUE
J 0
(-5790 2757);
DISPLAY 0.808511 (-5790 2757);
PAINT GREEN (-5790 2757);
DISPLAY INVISIBLE (-5790 2757);
FORCEPROP 2 LAST PATH I19
J 0
(-5750 2950);
DISPLAY 1.021277 (-5750 2950);
DISPLAY INVISIBLE (-5750 2950);
FORCEPROP 2 LAST $XR0 25E3<> 
J 0
(-5740 2850);
DISPLAY 0.638298 (-5740 2850);
PAINT MONO (-5740 2850);
FORCEADD OFFPAGE_IN..2
(-4600 6650);
FORCEPROP 2 LAST CDS_LIB cls
J 0
(-4600 6650);
DISPLAY INVISIBLE (-4600 6650);
FORCEPROP 1 LAST CDS_LMAN_SYM_OUTLINE -50,50,50,-50
J 0
(-4600 6650);
DISPLAY 0.468085 (-4600 6650);
PAINT GREEN (-4600 6650);
DISPLAY INVISIBLE (-4600 6650);
FORCEPROP 1 LAST BODY_TYPE COMMENT
J 0
(-4590 6785);
DISPLAY 0.808511 (-4590 6785);
PAINT GREEN (-4590 6785);
DISPLAY INVISIBLE (-4590 6785);
FORCEPROP 1 LAST OFFPAGE TRUE
J 0
(-4590 6705);
DISPLAY 0.808511 (-4590 6705);
PAINT GREEN (-4590 6705);
DISPLAY INVISIBLE (-4590 6705);
FORCEPROP 2 LAST PATH I30
J 0
(-4550 6750);
DISPLAY 1.021277 (-4550 6750);
DISPLAY INVISIBLE (-4550 6750);
FORCEPROP 2 LAST $XR0 21D4> 
J 0
(-4545 6650);
DISPLAY 0.638298 (-4545 6650);
PAINT MONO (-4545 6650);
FORCEADD OFFPAGE_IN..2
(-4600 6750);
FORCEPROP 1 LAST BODY_TYPE COMMENT
J 0
(-4590 6885);
DISPLAY 0.808511 (-4590 6885);
PAINT GREEN (-4590 6885);
DISPLAY INVISIBLE (-4590 6885);
FORCEPROP 1 LAST CDS_LMAN_SYM_OUTLINE -50,50,50,-50
J 0
(-4600 6750);
DISPLAY 0.468085 (-4600 6750);
PAINT GREEN (-4600 6750);
DISPLAY INVISIBLE (-4600 6750);
FORCEPROP 2 LAST CDS_LIB cls
J 0
(-4600 6750);
DISPLAY INVISIBLE (-4600 6750);
FORCEPROP 1 LAST OFFPAGE TRUE
J 0
(-4590 6805);
DISPLAY 0.808511 (-4590 6805);
PAINT GREEN (-4590 6805);
DISPLAY INVISIBLE (-4590 6805);
FORCEPROP 2 LAST PATH I31
J 0
(-4550 6850);
DISPLAY 1.021277 (-4550 6850);
DISPLAY INVISIBLE (-4550 6850);
FORCEPROP 2 LAST $XR0 21D4> 
J 0
(-4545 6750);
DISPLAY 0.638298 (-4545 6750);
PAINT MONO (-4545 6750);
FORCEADD OFFPAGE_OUT..1
(-4600 6050);
FORCEPROP 2 LAST CDS_LIB cls
J 0
(-4600 6050);
DISPLAY INVISIBLE (-4600 6050);
FORCEPROP 1 LAST CDS_LMAN_SYM_OUTLINE -50,50,50,-50
J 0
(-4600 6050);
DISPLAY 0.468085 (-4600 6050);
PAINT GREEN (-4600 6050);
DISPLAY INVISIBLE (-4600 6050);
FORCEPROP 1 LAST BODY_TYPE COMMENT
J 0
(-4590 6185);
DISPLAY 0.808511 (-4590 6185);
PAINT GREEN (-4590 6185);
DISPLAY INVISIBLE (-4590 6185);
FORCEPROP 1 LAST OFFPAGE TRUE
J 0
(-4590 6105);
DISPLAY 0.808511 (-4590 6105);
PAINT GREEN (-4590 6105);
DISPLAY INVISIBLE (-4590 6105);
FORCEPROP 2 LAST PATH I32
J 0
(-4550 6150);
DISPLAY 1.021277 (-4550 6150);
DISPLAY INVISIBLE (-4550 6150);
FORCEPROP 2 LAST $XR0 21D4< 
J 0
(-4545 6050);
DISPLAY 0.638298 (-4545 6050);
PAINT MONO (-4545 6050);
FORCEADD OFFPAGE_OUT..1
(-4600 6150);
FORCEPROP 2 LAST CDS_LIB cls
J 0
(-4600 6150);
DISPLAY INVISIBLE (-4600 6150);
FORCEPROP 1 LAST CDS_LMAN_SYM_OUTLINE -50,50,50,-50
J 0
(-4600 6150);
DISPLAY 0.468085 (-4600 6150);
PAINT GREEN (-4600 6150);
DISPLAY INVISIBLE (-4600 6150);
FORCEPROP 1 LAST BODY_TYPE COMMENT
J 0
(-4590 6285);
DISPLAY 0.808511 (-4590 6285);
PAINT GREEN (-4590 6285);
DISPLAY INVISIBLE (-4590 6285);
FORCEPROP 1 LAST OFFPAGE TRUE
J 0
(-4590 6205);
DISPLAY 0.808511 (-4590 6205);
PAINT GREEN (-4590 6205);
DISPLAY INVISIBLE (-4590 6205);
FORCEPROP 2 LAST PATH I33
J 0
(-4550 6250);
DISPLAY 1.021277 (-4550 6250);
DISPLAY INVISIBLE (-4550 6250);
FORCEPROP 2 LAST $XR0 21C4< 
J 0
(-4545 6150);
DISPLAY 0.638298 (-4545 6150);
PAINT MONO (-4545 6150);
FORCEADD OFFPAGE_OUT..1
(-4600 5750);
FORCEPROP 1 LAST BODY_TYPE COMMENT
J 0
(-4590 5885);
DISPLAY 0.808511 (-4590 5885);
PAINT GREEN (-4590 5885);
DISPLAY INVISIBLE (-4590 5885);
FORCEPROP 1 LAST CDS_LMAN_SYM_OUTLINE -50,50,50,-50
J 0
(-4600 5750);
DISPLAY 0.468085 (-4600 5750);
PAINT GREEN (-4600 5750);
DISPLAY INVISIBLE (-4600 5750);
FORCEPROP 2 LAST CDS_LIB cls
J 0
(-4600 5750);
DISPLAY INVISIBLE (-4600 5750);
FORCEPROP 1 LAST OFFPAGE TRUE
J 0
(-4590 5805);
DISPLAY 0.808511 (-4590 5805);
PAINT GREEN (-4590 5805);
DISPLAY INVISIBLE (-4590 5805);
FORCEPROP 2 LAST PATH I34
J 0
(-4500 5800);
DISPLAY 1.021277 (-4500 5800);
DISPLAY INVISIBLE (-4500 5800);
FORCEPROP 2 LAST $XR0 21C4< 
J 0
(-4545 5750);
DISPLAY 0.638298 (-4545 5750);
PAINT MONO (-4545 5750);
FORCEADD OFFPAGE_OUT..1
(-4600 5650);
FORCEPROP 2 LAST CDS_LIB cls
J 0
(-4600 5650);
DISPLAY INVISIBLE (-4600 5650);
FORCEPROP 1 LAST CDS_LMAN_SYM_OUTLINE -50,50,50,-50
J 0
(-4600 5650);
DISPLAY 0.468085 (-4600 5650);
PAINT GREEN (-4600 5650);
DISPLAY INVISIBLE (-4600 5650);
FORCEPROP 1 LAST BODY_TYPE COMMENT
J 0
(-4590 5785);
DISPLAY 0.808511 (-4590 5785);
PAINT GREEN (-4590 5785);
DISPLAY INVISIBLE (-4590 5785);
FORCEPROP 1 LAST OFFPAGE TRUE
J 0
(-4590 5705);
DISPLAY 0.808511 (-4590 5705);
PAINT GREEN (-4590 5705);
DISPLAY INVISIBLE (-4590 5705);
FORCEPROP 2 LAST PATH I35
J 0
(-4500 5700);
DISPLAY 1.021277 (-4500 5700);
DISPLAY INVISIBLE (-4500 5700);
FORCEPROP 2 LAST $XR0 21C4< 
J 0
(-4545 5650);
DISPLAY 0.638298 (-4545 5650);
PAINT MONO (-4545 5650);
FORCEADD RESISTOR..1
(-5600 5250);
FORCEPROP 1 LAST $LOCATION R278
J 2
(-5800 5250);
DISPLAY 1.212766 (-5800 5250);
PAINT GREEN (-5800 5250);
FORCEPROP 0 LAST CDS_LOCATION R278
J 0
(-5400 5350);
DISPLAY 1.021277 (-5400 5350);
DISPLAY INVISIBLE (-5400 5350);
FORCEPROP 0 LAST $SEC 1
J 0
(-5400 5350);
DISPLAY 0.680851 (-5400 5350);
PAINT MONO (-5400 5350);
DISPLAY INVISIBLE (-5400 5350);
FORCEPROP 0 LAST CDS_SEC 1
J 0
(-5400 5350);
DISPLAY 1.021277 (-5400 5350);
DISPLAY INVISIBLE (-5400 5350);
FORCEPROP 0 LASTPIN (-5700 5250) $PN 1
J 2
(-5710 5260);
DISPLAY 0.680851 (-5710 5260);
PAINT MONO (-5710 5260);
FORCEPROP 0 LASTPIN (-5450 5250) $PN 2
J 0
(-5440 5260);
DISPLAY 0.680851 (-5440 5260);
PAINT MONO (-5440 5260);
FORCEPROP 1 LAST VALUE 100OHM
J 0
(-5400 5250);
DISPLAY 1.212766 (-5400 5250);
PAINT GREEN (-5400 5250);
FORCEPROP 0 LAST PACKAGE 0402
J 0
(-5650 5300);
DISPLAY 1.021277 (-5650 5300);
FORCEPROP 1 LAST PATH I36
J 0
(-5797 5355);
DISPLAY 1.212766 (-5797 5355);
PAINT GREEN (-5797 5355);
DISPLAY INVISIBLE (-5797 5355);
FORCEPROP 1 LAST TOLERANCE 1%
J 0
(-5797 5505);
DISPLAY 1.212766 (-5797 5505);
PAINT GREEN (-5797 5505);
DISPLAY INVISIBLE (-5797 5505);
FORCEPROP 1 LAST CLS_PN G155-11000-01
J 0
(-5736 5450);
DISPLAY 1.212766 (-5736 5450);
PAINT GREEN (-5736 5450);
DISPLAY INVISIBLE (-5736 5450);
FORCEPROP 1 LAST CDS_LMAN_SYM_OUTLINE -50,50,100,-50
J 0
(-5600 5250);
DISPLAY 0.468085 (-5600 5250);
PAINT GREEN (-5600 5250);
DISPLAY INVISIBLE (-5600 5250);
FORCEPROP 2 LAST CDS_LIB passive
J 0
(-5600 5250);
DISPLAY INVISIBLE (-5600 5250);
FORCEADD RESISTOR..1
(-5450 5850);
FORCEPROP 1 LAST $LOCATION R277
J 2
(-5650 5850);
DISPLAY 1.212766 (-5650 5850);
PAINT GREEN (-5650 5850);
FORCEPROP 0 LAST CDS_LOCATION R277
J 0
(-5250 5950);
DISPLAY 1.021277 (-5250 5950);
DISPLAY INVISIBLE (-5250 5950);
FORCEPROP 0 LAST $SEC 1
J 0
(-5250 5950);
DISPLAY 0.680851 (-5250 5950);
PAINT MONO (-5250 5950);
DISPLAY INVISIBLE (-5250 5950);
FORCEPROP 0 LAST CDS_SEC 1
J 0
(-5250 5950);
DISPLAY 1.021277 (-5250 5950);
DISPLAY INVISIBLE (-5250 5950);
FORCEPROP 0 LASTPIN (-5550 5850) $PN 1
J 2
(-5560 5860);
DISPLAY 0.680851 (-5560 5860);
PAINT MONO (-5560 5860);
FORCEPROP 0 LASTPIN (-5300 5850) $PN 2
J 0
(-5290 5860);
DISPLAY 0.680851 (-5290 5860);
PAINT MONO (-5290 5860);
FORCEPROP 0 LAST NO_ASSY TRUE
J 0
(-5850 5950);
DISPLAY 1.021277 (-5850 5950);
DISPLAY BOTH (-5850 5950);
FORCEPROP 1 LAST VALUE 100OHM
J 0
(-5250 5850);
DISPLAY 1.212766 (-5250 5850);
PAINT GREEN (-5250 5850);
FORCEPROP 0 LAST PACKAGE 0402
J 0
(-5500 5900);
DISPLAY 0.808511 (-5500 5900);
FORCEPROP 1 LAST PATH I37
J 0
(-5647 5955);
DISPLAY 1.212766 (-5647 5955);
PAINT GREEN (-5647 5955);
DISPLAY INVISIBLE (-5647 5955);
FORCEPROP 1 LAST TOLERANCE 1%
J 0
(-5647 6105);
DISPLAY 1.212766 (-5647 6105);
PAINT GREEN (-5647 6105);
DISPLAY INVISIBLE (-5647 6105);
FORCEPROP 1 LAST CLS_PN G155-11000-01
J 0
(-5586 6050);
DISPLAY 1.212766 (-5586 6050);
PAINT GREEN (-5586 6050);
DISPLAY INVISIBLE (-5586 6050);
FORCEPROP 1 LAST CDS_LMAN_SYM_OUTLINE -50,50,100,-50
J 0
(-5450 5850);
DISPLAY 0.468085 (-5450 5850);
PAINT GREEN (-5450 5850);
DISPLAY INVISIBLE (-5450 5850);
FORCEPROP 2 LAST CDS_LIB passive
J 0
(-5450 5850);
DISPLAY INVISIBLE (-5450 5850);
FORCEADD RESISTOR..1
(-5450 6250);
FORCEPROP 1 LAST $LOCATION R276
J 2
(-5650 6250);
DISPLAY 1.212766 (-5650 6250);
PAINT GREEN (-5650 6250);
FORCEPROP 0 LAST CDS_LOCATION R276
J 0
(-5250 6350);
DISPLAY 1.021277 (-5250 6350);
DISPLAY INVISIBLE (-5250 6350);
FORCEPROP 0 LAST $SEC 1
J 0
(-5250 6350);
DISPLAY 0.680851 (-5250 6350);
PAINT MONO (-5250 6350);
DISPLAY INVISIBLE (-5250 6350);
FORCEPROP 0 LAST CDS_SEC 1
J 0
(-5250 6350);
DISPLAY 1.021277 (-5250 6350);
DISPLAY INVISIBLE (-5250 6350);
FORCEPROP 0 LASTPIN (-5550 6250) $PN 1
J 2
(-5560 6260);
DISPLAY 0.680851 (-5560 6260);
PAINT MONO (-5560 6260);
FORCEPROP 0 LASTPIN (-5300 6250) $PN 2
J 0
(-5290 6260);
DISPLAY 0.680851 (-5290 6260);
PAINT MONO (-5290 6260);
FORCEPROP 0 LAST PACKAGE 0402
J 0
(-5500 6300);
DISPLAY 0.808511 (-5500 6300);
FORCEPROP 1 LAST VALUE 100OHM
J 0
(-5250 6250);
DISPLAY 1.212766 (-5250 6250);
PAINT GREEN (-5250 6250);
FORCEPROP 0 LAST NO_ASSY TRUE
J 0
(-5850 6350);
DISPLAY 1.021277 (-5850 6350);
DISPLAY BOTH (-5850 6350);
FORCEPROP 1 LAST PATH I38
J 0
(-5647 6355);
DISPLAY 1.212766 (-5647 6355);
PAINT GREEN (-5647 6355);
DISPLAY INVISIBLE (-5647 6355);
FORCEPROP 1 LAST TOLERANCE 1%
J 0
(-5647 6505);
DISPLAY 1.212766 (-5647 6505);
PAINT GREEN (-5647 6505);
DISPLAY INVISIBLE (-5647 6505);
FORCEPROP 1 LAST CLS_PN G155-11000-01
J 0
(-5586 6450);
DISPLAY 1.212766 (-5586 6450);
PAINT GREEN (-5586 6450);
DISPLAY INVISIBLE (-5586 6450);
FORCEPROP 1 LAST CDS_LMAN_SYM_OUTLINE -50,50,100,-50
J 0
(-5450 6250);
DISPLAY 0.468085 (-5450 6250);
PAINT GREEN (-5450 6250);
DISPLAY INVISIBLE (-5450 6250);
FORCEPROP 2 LAST CDS_LIB passive
J 0
(-5450 6250);
DISPLAY INVISIBLE (-5450 6250);
FORCEADD RESISTOR..1
(-5550 6850);
FORCEPROP 1 LAST $LOCATION R275
J 2
(-5750 6850);
DISPLAY 1.212766 (-5750 6850);
PAINT GREEN (-5750 6850);
FORCEPROP 0 LAST CDS_LOCATION R275
J 0
(-5350 6950);
DISPLAY 1.021277 (-5350 6950);
DISPLAY INVISIBLE (-5350 6950);
FORCEPROP 0 LAST $SEC 1
J 0
(-5350 6950);
DISPLAY 0.680851 (-5350 6950);
PAINT MONO (-5350 6950);
DISPLAY INVISIBLE (-5350 6950);
FORCEPROP 0 LAST CDS_SEC 1
J 0
(-5350 6950);
DISPLAY 1.021277 (-5350 6950);
DISPLAY INVISIBLE (-5350 6950);
FORCEPROP 0 LASTPIN (-5650 6850) $PN 1
J 2
(-5660 6860);
DISPLAY 0.680851 (-5660 6860);
PAINT MONO (-5660 6860);
FORCEPROP 0 LASTPIN (-5400 6850) $PN 2
J 0
(-5390 6860);
DISPLAY 0.680851 (-5390 6860);
PAINT MONO (-5390 6860);
FORCEPROP 1 LAST VALUE 100OHM
J 0
(-5350 6850);
DISPLAY 1.212766 (-5350 6850);
PAINT GREEN (-5350 6850);
FORCEPROP 0 LAST PACKAGE 0402
J 0
(-5600 6900);
DISPLAY 0.808511 (-5600 6900);
FORCEPROP 0 LAST NO_ASSY TRUE
J 0
(-5950 6950);
DISPLAY 1.021277 (-5950 6950);
DISPLAY BOTH (-5950 6950);
FORCEPROP 1 LAST CLS_PN G155-11000-01
J 0
(-5686 7050);
DISPLAY 1.212766 (-5686 7050);
PAINT GREEN (-5686 7050);
DISPLAY INVISIBLE (-5686 7050);
FORCEPROP 1 LAST CDS_LMAN_SYM_OUTLINE -50,50,100,-50
J 0
(-5550 6850);
DISPLAY 0.468085 (-5550 6850);
PAINT GREEN (-5550 6850);
DISPLAY INVISIBLE (-5550 6850);
FORCEPROP 2 LAST CDS_LIB passive
J 0
(-5550 6850);
DISPLAY INVISIBLE (-5550 6850);
FORCEPROP 1 LAST TOLERANCE 1%
J 0
(-5747 7105);
DISPLAY 1.212766 (-5747 7105);
PAINT GREEN (-5747 7105);
DISPLAY INVISIBLE (-5747 7105);
FORCEPROP 1 LAST PATH I39
J 0
(-5747 6955);
DISPLAY 1.212766 (-5747 6955);
PAINT GREEN (-5747 6955);
DISPLAY INVISIBLE (-5747 6955);
FORCEADD OFFPAGE_IN..2
(-4600 5150);
FORCEPROP 1 LAST CDS_LMAN_SYM_OUTLINE -50,50,50,-50
J 0
(-4600 5150);
DISPLAY 0.468085 (-4600 5150);
PAINT GREEN (-4600 5150);
DISPLAY INVISIBLE (-4600 5150);
FORCEPROP 2 LAST CDS_LIB cls
J 0
(-4600 5150);
DISPLAY INVISIBLE (-4600 5150);
FORCEPROP 1 LAST BODY_TYPE COMMENT
J 0
(-4590 5285);
DISPLAY 0.808511 (-4590 5285);
PAINT GREEN (-4590 5285);
DISPLAY INVISIBLE (-4590 5285);
FORCEPROP 1 LAST OFFPAGE TRUE
J 0
(-4590 5205);
DISPLAY 0.808511 (-4590 5205);
PAINT GREEN (-4590 5205);
DISPLAY INVISIBLE (-4590 5205);
FORCEPROP 2 LAST PATH I4
J 0
(-4550 5250);
DISPLAY 1.021277 (-4550 5250);
DISPLAY INVISIBLE (-4550 5250);
FORCEPROP 2 LAST $XR0 15D12> 
J 0
(-4545 5150);
DISPLAY 0.638298 (-4545 5150);
PAINT MONO (-4545 5150);
FORCEADD OFFPAGE_BI..1
R 4
(-11100 2950);
FORCEPROP 1 LAST BODY_TYPE COMMENT
R 2
J 0
(-11110 2815);
DISPLAY 0.808511 (-11110 2815);
PAINT GREEN (-11110 2815);
DISPLAY INVISIBLE (-11110 2815);
FORCEPROP 1 LAST CDS_LMAN_SYM_OUTLINE -50,50,50,-50
R 2
J 0
(-11100 2950);
DISPLAY 0.468085 (-11100 2950);
PAINT GREEN (-11100 2950);
DISPLAY INVISIBLE (-11100 2950);
FORCEPROP 2 LAST CDS_LIB cls
J 0
(-11100 2950);
DISPLAY INVISIBLE (-11100 2950);
FORCEPROP 1 LAST OFFPAGE TRUE
R 2
J 0
(-11110 2895);
DISPLAY 0.808511 (-11110 2895);
PAINT GREEN (-11110 2895);
DISPLAY INVISIBLE (-11110 2895);
FORCEPROP 2 LAST PATH I40
J 0
(-11350 3000);
DISPLAY 1.021277 (-11350 3000);
DISPLAY INVISIBLE (-11350 3000);
FORCEPROP 2 LAST $XR0 25F2<> 
J 0
(-11319 2950);
DISPLAY 0.638298 (-11319 2950);
PAINT MONO (-11319 2950);
FORCEADD OFFPAGE_BI..1
R 4
(-11100 2850);
FORCEPROP 1 LAST BODY_TYPE COMMENT
R 2
J 0
(-11110 2715);
DISPLAY 0.808511 (-11110 2715);
PAINT GREEN (-11110 2715);
DISPLAY INVISIBLE (-11110 2715);
FORCEPROP 1 LAST CDS_LMAN_SYM_OUTLINE -50,50,50,-50
R 2
J 0
(-11100 2850);
DISPLAY 0.468085 (-11100 2850);
PAINT GREEN (-11100 2850);
DISPLAY INVISIBLE (-11100 2850);
FORCEPROP 2 LAST CDS_LIB cls
J 0
(-11100 2850);
DISPLAY INVISIBLE (-11100 2850);
FORCEPROP 1 LAST OFFPAGE TRUE
R 2
J 0
(-11110 2795);
DISPLAY 0.808511 (-11110 2795);
PAINT GREEN (-11110 2795);
DISPLAY INVISIBLE (-11110 2795);
FORCEPROP 2 LAST PATH I41
J 0
(-11350 2900);
DISPLAY 1.021277 (-11350 2900);
DISPLAY INVISIBLE (-11350 2900);
FORCEPROP 2 LAST $XR0 25F2<> 
J 0
(-11319 2850);
DISPLAY 0.638298 (-11319 2850);
PAINT MONO (-11319 2850);
FORCEADD OFFPAGE_BI..1
R 4
(-11100 3150);
FORCEPROP 1 LAST BODY_TYPE COMMENT
R 2
J 0
(-11110 3015);
DISPLAY 0.808511 (-11110 3015);
PAINT GREEN (-11110 3015);
DISPLAY INVISIBLE (-11110 3015);
FORCEPROP 1 LAST CDS_LMAN_SYM_OUTLINE -50,50,50,-50
R 2
J 0
(-11100 3150);
DISPLAY 0.468085 (-11100 3150);
PAINT GREEN (-11100 3150);
DISPLAY INVISIBLE (-11100 3150);
FORCEPROP 2 LAST CDS_LIB cls
J 0
(-11100 3150);
DISPLAY INVISIBLE (-11100 3150);
FORCEPROP 1 LAST OFFPAGE TRUE
R 2
J 0
(-11110 3095);
DISPLAY 0.808511 (-11110 3095);
PAINT GREEN (-11110 3095);
DISPLAY INVISIBLE (-11110 3095);
FORCEPROP 2 LAST PATH I42
J 0
(-11350 3200);
DISPLAY 1.021277 (-11350 3200);
DISPLAY INVISIBLE (-11350 3200);
FORCEPROP 2 LAST $XR0 25F2<> 
J 0
(-11319 3150);
DISPLAY 0.638298 (-11319 3150);
PAINT MONO (-11319 3150);
FORCEADD OFFPAGE_BI..1
R 4
(-11100 3050);
FORCEPROP 1 LAST BODY_TYPE COMMENT
R 2
J 0
(-11110 2915);
DISPLAY 0.808511 (-11110 2915);
PAINT GREEN (-11110 2915);
DISPLAY INVISIBLE (-11110 2915);
FORCEPROP 1 LAST CDS_LMAN_SYM_OUTLINE -50,50,50,-50
R 2
J 0
(-11100 3050);
DISPLAY 0.468085 (-11100 3050);
PAINT GREEN (-11100 3050);
DISPLAY INVISIBLE (-11100 3050);
FORCEPROP 2 LAST CDS_LIB cls
J 0
(-11100 3050);
DISPLAY INVISIBLE (-11100 3050);
FORCEPROP 1 LAST OFFPAGE TRUE
R 2
J 0
(-11110 2995);
DISPLAY 0.808511 (-11110 2995);
PAINT GREEN (-11110 2995);
DISPLAY INVISIBLE (-11110 2995);
FORCEPROP 2 LAST PATH I43
J 0
(-11350 3100);
DISPLAY 1.021277 (-11350 3100);
DISPLAY INVISIBLE (-11350 3100);
FORCEPROP 2 LAST $XR0 25F2<> 
J 0
(-11319 3050);
DISPLAY 0.638298 (-11319 3050);
PAINT MONO (-11319 3050);
FORCEADD OFFPAGE_BI..1
R 4
(-11100 3250);
FORCEPROP 2 LAST CDS_LIB cls
J 0
(-11100 3250);
DISPLAY INVISIBLE (-11100 3250);
FORCEPROP 1 LAST CDS_LMAN_SYM_OUTLINE -50,50,50,-50
R 2
J 0
(-11100 3250);
DISPLAY 0.468085 (-11100 3250);
PAINT GREEN (-11100 3250);
DISPLAY INVISIBLE (-11100 3250);
FORCEPROP 1 LAST BODY_TYPE COMMENT
R 2
J 0
(-11110 3115);
DISPLAY 0.808511 (-11110 3115);
PAINT GREEN (-11110 3115);
DISPLAY INVISIBLE (-11110 3115);
FORCEPROP 1 LAST OFFPAGE TRUE
R 2
J 0
(-11110 3195);
DISPLAY 0.808511 (-11110 3195);
PAINT GREEN (-11110 3195);
DISPLAY INVISIBLE (-11110 3195);
FORCEPROP 2 LAST PATH I44
J 0
(-11350 3300);
DISPLAY 1.021277 (-11350 3300);
DISPLAY INVISIBLE (-11350 3300);
FORCEPROP 2 LAST $XR0 25F2<> 
J 0
(-11319 3250);
DISPLAY 0.638298 (-11319 3250);
PAINT MONO (-11319 3250);
FORCEADD OFFPAGE_BI..1
R 4
(-11100 3350);
FORCEPROP 2 LAST CDS_LIB cls
J 0
(-11100 3350);
DISPLAY INVISIBLE (-11100 3350);
FORCEPROP 1 LAST CDS_LMAN_SYM_OUTLINE -50,50,50,-50
R 2
J 0
(-11100 3350);
DISPLAY 0.468085 (-11100 3350);
PAINT GREEN (-11100 3350);
DISPLAY INVISIBLE (-11100 3350);
FORCEPROP 1 LAST BODY_TYPE COMMENT
R 2
J 0
(-11110 3215);
DISPLAY 0.808511 (-11110 3215);
PAINT GREEN (-11110 3215);
DISPLAY INVISIBLE (-11110 3215);
FORCEPROP 1 LAST OFFPAGE TRUE
R 2
J 0
(-11110 3295);
DISPLAY 0.808511 (-11110 3295);
PAINT GREEN (-11110 3295);
DISPLAY INVISIBLE (-11110 3295);
FORCEPROP 2 LAST PATH I45
J 0
(-11350 3400);
DISPLAY 1.021277 (-11350 3400);
DISPLAY INVISIBLE (-11350 3400);
FORCEPROP 2 LAST $XR0 25F2<> 
J 0
(-11319 3350);
DISPLAY 0.638298 (-11319 3350);
PAINT MONO (-11319 3350);
FORCEADD OFFPAGE_BI..1
R 4
(-11100 3450);
FORCEPROP 2 LAST CDS_LIB cls
J 0
(-11100 3450);
DISPLAY INVISIBLE (-11100 3450);
FORCEPROP 1 LAST CDS_LMAN_SYM_OUTLINE -50,50,50,-50
R 2
J 0
(-11100 3450);
DISPLAY 0.468085 (-11100 3450);
PAINT GREEN (-11100 3450);
DISPLAY INVISIBLE (-11100 3450);
FORCEPROP 1 LAST BODY_TYPE COMMENT
R 2
J 0
(-11110 3315);
DISPLAY 0.808511 (-11110 3315);
PAINT GREEN (-11110 3315);
DISPLAY INVISIBLE (-11110 3315);
FORCEPROP 1 LAST OFFPAGE TRUE
R 2
J 0
(-11110 3395);
DISPLAY 0.808511 (-11110 3395);
PAINT GREEN (-11110 3395);
DISPLAY INVISIBLE (-11110 3395);
FORCEPROP 2 LAST PATH I46
J 0
(-11350 3500);
DISPLAY 1.021277 (-11350 3500);
DISPLAY INVISIBLE (-11350 3500);
FORCEPROP 2 LAST $XR0 25F2<> 
J 0
(-11319 3450);
DISPLAY 0.638298 (-11319 3450);
PAINT MONO (-11319 3450);
FORCEADD OFFPAGE_BI..1
R 4
(-11100 3550);
FORCEPROP 2 LAST CDS_LIB cls
J 0
(-11100 3550);
DISPLAY INVISIBLE (-11100 3550);
FORCEPROP 1 LAST CDS_LMAN_SYM_OUTLINE -50,50,50,-50
R 2
J 0
(-11100 3550);
DISPLAY 0.468085 (-11100 3550);
PAINT GREEN (-11100 3550);
DISPLAY INVISIBLE (-11100 3550);
FORCEPROP 1 LAST BODY_TYPE COMMENT
R 2
J 0
(-11110 3415);
DISPLAY 0.808511 (-11110 3415);
PAINT GREEN (-11110 3415);
DISPLAY INVISIBLE (-11110 3415);
FORCEPROP 1 LAST OFFPAGE TRUE
R 2
J 0
(-11110 3495);
DISPLAY 0.808511 (-11110 3495);
PAINT GREEN (-11110 3495);
DISPLAY INVISIBLE (-11110 3495);
FORCEPROP 2 LAST PATH I47
J 0
(-11350 3600);
DISPLAY 1.021277 (-11350 3600);
DISPLAY INVISIBLE (-11350 3600);
FORCEPROP 2 LAST $XR0 25F2<> 
J 0
(-11319 3550);
DISPLAY 0.638298 (-11319 3550);
PAINT MONO (-11319 3550);
FORCEADD OFFPAGE_BI..1
R 4
(-11100 3650);
FORCEPROP 2 LAST CDS_LIB cls
J 0
(-11100 3650);
DISPLAY INVISIBLE (-11100 3650);
FORCEPROP 1 LAST CDS_LMAN_SYM_OUTLINE -50,50,50,-50
R 2
J 0
(-11100 3650);
DISPLAY 0.468085 (-11100 3650);
PAINT GREEN (-11100 3650);
DISPLAY INVISIBLE (-11100 3650);
FORCEPROP 1 LAST BODY_TYPE COMMENT
R 2
J 0
(-11110 3515);
DISPLAY 0.808511 (-11110 3515);
PAINT GREEN (-11110 3515);
DISPLAY INVISIBLE (-11110 3515);
FORCEPROP 1 LAST OFFPAGE TRUE
R 2
J 0
(-11110 3595);
DISPLAY 0.808511 (-11110 3595);
PAINT GREEN (-11110 3595);
DISPLAY INVISIBLE (-11110 3595);
FORCEPROP 2 LAST PATH I48
J 0
(-11350 3700);
DISPLAY 1.021277 (-11350 3700);
DISPLAY INVISIBLE (-11350 3700);
FORCEPROP 2 LAST $XR0 25F2<> 
J 0
(-11319 3650);
DISPLAY 0.638298 (-11319 3650);
PAINT MONO (-11319 3650);
FORCEADD OFFPAGE_BI..1
R 4
(-11100 3750);
FORCEPROP 2 LAST CDS_LIB cls
J 0
(-11100 3750);
DISPLAY INVISIBLE (-11100 3750);
FORCEPROP 1 LAST CDS_LMAN_SYM_OUTLINE -50,50,50,-50
R 2
J 0
(-11100 3750);
DISPLAY 0.468085 (-11100 3750);
PAINT GREEN (-11100 3750);
DISPLAY INVISIBLE (-11100 3750);
FORCEPROP 1 LAST BODY_TYPE COMMENT
R 2
J 0
(-11110 3615);
DISPLAY 0.808511 (-11110 3615);
PAINT GREEN (-11110 3615);
DISPLAY INVISIBLE (-11110 3615);
FORCEPROP 1 LAST OFFPAGE TRUE
R 2
J 0
(-11110 3695);
DISPLAY 0.808511 (-11110 3695);
PAINT GREEN (-11110 3695);
DISPLAY INVISIBLE (-11110 3695);
FORCEPROP 2 LAST PATH I49
J 0
(-11350 3800);
DISPLAY 1.021277 (-11350 3800);
DISPLAY INVISIBLE (-11350 3800);
FORCEPROP 2 LAST $XR0 25E2<> 
J 0
(-11319 3750);
DISPLAY 0.638298 (-11319 3750);
PAINT MONO (-11319 3750);
FORCEADD OFFPAGE_IN..2
(-4600 5050);
FORCEPROP 1 LAST BODY_TYPE COMMENT
J 0
(-4590 5185);
DISPLAY 0.808511 (-4590 5185);
PAINT GREEN (-4590 5185);
DISPLAY INVISIBLE (-4590 5185);
FORCEPROP 2 LAST CDS_LIB cls
J 0
(-4600 5050);
DISPLAY INVISIBLE (-4600 5050);
FORCEPROP 1 LAST CDS_LMAN_SYM_OUTLINE -50,50,50,-50
J 0
(-4600 5050);
DISPLAY 0.468085 (-4600 5050);
PAINT GREEN (-4600 5050);
DISPLAY INVISIBLE (-4600 5050);
FORCEPROP 1 LAST OFFPAGE TRUE
J 0
(-4590 5105);
DISPLAY 0.808511 (-4590 5105);
PAINT GREEN (-4590 5105);
DISPLAY INVISIBLE (-4590 5105);
FORCEPROP 2 LAST PATH I5
J 0
(-4550 5150);
DISPLAY 1.021277 (-4550 5150);
DISPLAY INVISIBLE (-4550 5150);
FORCEPROP 2 LAST $XR0 15D12> 
J 0
(-4545 5050);
DISPLAY 0.638298 (-4545 5050);
PAINT MONO (-4545 5050);
FORCEADD SHEET_A1..1
(-200 -300);
FORCEPROP 2 LAST CUSTOM_TXT_CDS <XR_PAGE_TITLE>
J 0
(-15770 11050);
DISPLAY 0.638298 (-15770 11050);
PAINT PINK (-15770 11050);
FORCEPROP 1 LAST CUSTOM_TXT_CDS <DOCNO>
J 0
(-2250 85);
DISPLAY 0.978723 (-2250 85);
FORCEPROP 1 LAST CUSTOM_TXT_CDS <CON_PAGE_NUM>
J 0
(-2355 -250);
DISPLAY 0.978723 (-2355 -250);
FORCEPROP 1 LAST CUSTOM_TXT_CDS <DATE>
J 0
(-900 -125);
DISPLAY 0.978723 (-900 -125);
FORCEPROP 1 LAST CUSTOM_TXT_CDS <TITLE>
J 1
(-1985 330);
DISPLAY 0.978723 (-1985 330);
FORCEPROP 1 LAST CUSTOM_TXT_CDS <DESIGNER>
J 0
(-900 300);
DISPLAY 0.978723 (-900 300);
FORCEPROP 1 LAST CUSTOM_TXT_CDS <CON_TOTAL_PAGES>
J 0
(-2045 -250);
DISPLAY 0.808511 (-2045 -250);
FORCEPROP 1 LAST CUSTOM_TXT_CDS <ASSY_PN>
J 0
(-2250 -125);
DISPLAY 0.978723 (-2250 -125);
FORCEPROP 1 LAST CUSTOM_TXT_CDS <DOCREV>
J 0
(-900 75);
DISPLAY 0.978723 (-900 75);
FORCEPROP 1 LAST TITLE FPGA_4/5
J 0
(-2700 600);
DISPLAY 3.042553 (-2700 600);
PAINT GREEN (-2700 600);
FORCEPROP 2 LAST CDS_LIB cls
J 0
(-200 -300);
DISPLAY INVISIBLE (-200 -300);
FORCEPROP 1 LAST CDS_LMAN_SYM_OUTLINE -15850,11500,200,-200
J 0
(-200 -300);
DISPLAY 0.468085 (-200 -300);
PAINT GREEN (-200 -300);
DISPLAY INVISIBLE (-200 -300);
FORCEPROP 2 LAST PAGE_BORDER TRUE
J 0
(-15770 11050);
DISPLAY 0.638298 (-15770 11050);
PAINT PINK (-15770 11050);
DISPLAY INVISIBLE (-15770 11050);
FORCEPROP 1 LAST COMMENT_BODY TRUE
J 0
(-190 -245);
DISPLAY 0.808511 (-190 -245);
DISPLAY INVISIBLE (-190 -245);
FORCEPROP 2 LAST CDS_XR_PAGE_TITLE CR-13 : @TIMECARD_LIB.TIMECARD(SCH_1):PAGE13
J 0
(-15770 11050);
DISPLAY 0.638298 (-15770 11050);
PAINT PINK (-15770 11050);
DISPLAY INVISIBLE (-15770 11050);
WIRE 16 -1 (-3050 6450)(-3050 6350);
WIRE 16 -1 (-3050 6450)(-3250 6450);
WIRE 16 -1 (-3700 6450)(-3250 6450);
WIRE 16 -1 (-3250 6550)(-3250 6450);
WIRE 16 -1 (-3700 6550)(-3250 6550);
WIRE 16 -1 (-3700 6950)(-3250 6950);
WIRE 16 -1 (-3250 6950)(-3250 6850);
WIRE 16 -1 (-2950 6850)(-3250 6850);
WIRE 16 -1 (-3250 6850)(-3700 6850);
WIRE 16 -1 (-2950 6950)(-2950 6850);
WIRE 16 -1 (-3700 5350)(-3250 5350);
WIRE 16 -1 (-3250 5350)(-3250 5250);
WIRE 16 -1 (-2950 5250)(-3250 5250);
WIRE 16 -1 (-3250 5250)(-3700 5250);
WIRE 16 -1 (-2950 5350)(-2950 5250);
WIRE 16 -1 (-3050 4850)(-3050 4750);
WIRE 16 -1 (-3050 4850)(-3250 4850);
WIRE 16 -1 (-3700 4850)(-3250 4850);
WIRE 16 -1 (-3250 4950)(-3250 4850);
WIRE 16 -1 (-3700 4950)(-3250 4950);
WIRE 16 -1 (-4750 4850)(-3950 4850);
WIRE 16 -1 (-4750 5050)(-4750 4850);
WIRE 16 -1 (-4650 5050)(-4750 5050);
WIRE 16 -1 (-4800 5050)(-4750 5050);
WIRE 16 -1 (-4800 5350)(-4800 5050);
WIRE 16 -1 (-5000 5050)(-4800 5050);
WIRE 16 -1 (-5000 5250)(-5000 5050);
WIRE 16 -1 (-6700 5050)(-5000 5050);
FORCEPROP 2 LAST SIG_NAME MHZ200CLKN_CLKIN
J 0
(-6010 5060);
DISPLAY 1.021277 (-6010 5060);
WIRE 16 -1 (-4800 5350)(-3950 5350);
WIRE 16 -1 (-5450 5250)(-5000 5250);
WIRE 16 -1 (-4700 4950)(-3950 4950);
WIRE 16 -1 (-4700 5150)(-4700 4950);
WIRE 16 -1 (-4650 5150)(-4700 5150);
WIRE 16 -1 (-4750 5150)(-4700 5150);
WIRE 16 -1 (-4750 5150)(-4750 5250);
WIRE 16 -1 (-6100 5150)(-4750 5150);
FORCEPROP 2 LAST SIG_NAME MHZ200CLKP_CLKIN
J 0
(-6010 5160);
DISPLAY 1.021277 (-6010 5160);
WIRE 16 -1 (-6700 5150)(-6100 5150);
WIRE 16 -1 (-6100 5250)(-6100 5150);
WIRE 16 -1 (-4750 5250)(-3950 5250);
WIRE 16 -1 (-5700 5250)(-6100 5250);
WIRE 16 -1 (-5550 5850)(-6100 5850);
WIRE 16 -1 (-6100 5850)(-6100 5750);
WIRE 16 -1 (-6700 5750)(-6100 5750);
WIRE 16 -1 (-4650 5750)(-6100 5750);
FORCEPROP 2 LAST SIG_NAME FPGA_OUT_MAC_PPS_IN1P
J 0
(-6010 5760);
DISPLAY 1.021277 (-6010 5760);
WIRE 16 -1 (-5300 5850)(-4800 5850);
WIRE 16 -1 (-4800 5850)(-4800 5650);
WIRE 16 -1 (-4800 5650)(-4650 5650);
WIRE 16 -1 (-6700 5650)(-4800 5650);
FORCEPROP 2 LAST SIG_NAME FPGA_OUT_MAC_PPS_IN1N
J 0
(-6010 5660);
DISPLAY 1.021277 (-6010 5660);
WIRE 16 -1 (-5300 6250)(-4800 6250);
WIRE 16 -1 (-4800 6250)(-4800 6050);
WIRE 16 -1 (-4650 6050)(-4800 6050);
WIRE 16 -1 (-6700 6050)(-4800 6050);
FORCEPROP 2 LAST SIG_NAME FPGA_OUT_MAC_PPS_IN0N
J 0
(-6010 6060);
DISPLAY 1.021277 (-6010 6060);
WIRE 16 -1 (-6700 6150)(-6100 6150);
WIRE 16 -1 (-6100 6150)(-4650 6150);
FORCEPROP 2 LAST SIG_NAME FPGA_OUT_MAC_PPS_IN0P
J 0
(-6010 6160);
DISPLAY 1.021277 (-6010 6160);
WIRE 16 -1 (-6100 6250)(-6100 6150);
WIRE 16 -1 (-5550 6250)(-6100 6250);
WIRE 16 -1 (-3950 6450)(-4750 6450);
WIRE 16 -1 (-4750 6650)(-4750 6450);
WIRE 16 -1 (-4650 6650)(-4750 6650);
WIRE 16 -1 (-4750 6650)(-4800 6650);
WIRE 16 -1 (-4800 6950)(-4800 6650);
WIRE 16 -1 (-4800 6650)(-5000 6650);
WIRE 16 -1 (-5000 6850)(-5000 6650);
WIRE 16 -1 (-6700 6650)(-5000 6650);
FORCEPROP 2 LAST SIG_NAME FPGA_IN_MAC_PPS_OUTN
J 0
(-6010 6660);
DISPLAY 1.021277 (-6010 6660);
WIRE 16 -1 (-4800 6950)(-3950 6950);
WIRE 16 -1 (-5400 6850)(-5000 6850);
WIRE 16 -1 (-3950 6550)(-4700 6550);
WIRE 16 -1 (-4700 6750)(-4700 6550);
WIRE 16 -1 (-4650 6750)(-4700 6750);
WIRE 16 -1 (-4700 6750)(-4750 6750);
WIRE 16 -1 (-4750 6850)(-4750 6750);
WIRE 16 -1 (-6100 6750)(-4750 6750);
FORCEPROP 2 LAST SIG_NAME FPGA_IN_MAC_PPS_OUTP
J 0
(-6010 6760);
DISPLAY 1.021277 (-6010 6760);
WIRE 16 -1 (-6700 6750)(-6100 6750);
WIRE 16 -1 (-6100 6850)(-6100 6750);
WIRE 16 -1 (-4750 6850)(-3950 6850);
WIRE 16 -1 (-5650 6850)(-6100 6850);
WIRE 16 -1 (-6700 3350)(-5850 3350);
FORCEPROP 2 LAST SIG_NAME IO_L22P_34
J 0
(-6410 3360);
DISPLAY 1.021277 (-6410 3360);
WIRE 16 -1 (-6700 3250)(-5850 3250);
FORCEPROP 2 LAST SIG_NAME IO_L22N_34
J 0
(-6410 3260);
DISPLAY 1.021277 (-6410 3260);
WIRE 16 -1 (-6700 3750)(-5850 3750);
FORCEPROP 2 LAST SIG_NAME IO_L20P_34
J 0
(-6410 3760);
DISPLAY 1.021277 (-6410 3760);
WIRE 16 -1 (-11050 2850)(-9900 2850);
FORCEPROP 2 LAST SIG_NAME IO_L24N_35
J 0
(-11010 2860);
DISPLAY 1.021277 (-11010 2860);
WIRE 16 -1 (-11050 2950)(-9900 2950);
FORCEPROP 2 LAST SIG_NAME IO_L24P_35
J 0
(-11010 2960);
DISPLAY 1.021277 (-11010 2960);
WIRE 16 -1 (-11050 3050)(-9900 3050);
FORCEPROP 2 LAST SIG_NAME IO_L23N_35
J 0
(-11010 3060);
DISPLAY 1.021277 (-11010 3060);
WIRE 16 -1 (-11050 3150)(-9900 3150);
FORCEPROP 2 LAST SIG_NAME IO_L23P_35
J 0
(-11010 3160);
DISPLAY 1.021277 (-11010 3160);
WIRE 16 -1 (-11050 3250)(-9900 3250);
FORCEPROP 2 LAST SIG_NAME IO_L22N_35
J 0
(-11010 3260);
DISPLAY 1.021277 (-11010 3260);
WIRE 16 -1 (-11050 3350)(-9900 3350);
FORCEPROP 2 LAST SIG_NAME IO_L22P_35
J 0
(-11010 3360);
DISPLAY 1.021277 (-11010 3360);
WIRE 16 -1 (-11050 3450)(-9900 3450);
FORCEPROP 2 LAST SIG_NAME IO_L21N_35
J 0
(-11010 3460);
DISPLAY 1.021277 (-11010 3460);
WIRE 16 -1 (-11050 3550)(-9900 3550);
FORCEPROP 2 LAST SIG_NAME IO_L21P_35
J 0
(-11010 3560);
DISPLAY 1.021277 (-11010 3560);
WIRE 16 -1 (-11050 3650)(-9900 3650);
FORCEPROP 2 LAST SIG_NAME IO_L20N_35
J 0
(-11010 3660);
DISPLAY 1.021277 (-11010 3660);
WIRE 16 -1 (-11050 3750)(-9900 3750);
FORCEPROP 2 LAST SIG_NAME IO_L20P_35
J 0
(-11010 3760);
DISPLAY 1.021277 (-11010 3760);
WIRE 16 -1 (-6700 2950)(-5850 2950);
FORCEPROP 2 LAST SIG_NAME IO_L24P_34
J 0
(-6410 2960);
DISPLAY 1.021277 (-6410 2960);
WIRE 16 -1 (-6700 2850)(-5850 2850);
FORCEPROP 2 LAST SIG_NAME IO_L24N_34
J 0
(-6410 2860);
DISPLAY 1.021277 (-6410 2860);
WIRE 16 -1 (-6700 3050)(-5850 3050);
FORCEPROP 2 LAST SIG_NAME IO_L23N_34
J 0
(-6410 3060);
DISPLAY 1.021277 (-6410 3060);
WIRE 16 -1 (-6700 3150)(-5850 3150);
FORCEPROP 2 LAST SIG_NAME IO_L23P_34
J 0
(-6410 3160);
DISPLAY 1.021277 (-6410 3160);
WIRE 16 -1 (-6700 3550)(-5850 3550);
FORCEPROP 2 LAST SIG_NAME IO_L21P_34
J 0
(-6410 3560);
DISPLAY 1.021277 (-6410 3560);
WIRE 16 -1 (-6700 3450)(-5850 3450);
FORCEPROP 2 LAST SIG_NAME IO_L21N_34
J 0
(-6410 3460);
DISPLAY 1.021277 (-6410 3460);
WIRE 16 -1 (-6700 3650)(-5850 3650);
FORCEPROP 2 LAST SIG_NAME IO_L20N_34
J 0
(-6410 3660);
DISPLAY 1.021277 (-6410 3660);
DOT 1 (-3250 6850);
DOT 1 (-3250 6450);
DOT 1 (-3250 5250);
DOT 1 (-3250 4850);
DOT 1 (-4700 6750);
DOT 1 (-4750 6750);
DOT 1 (-4750 6650);
DOT 1 (-4800 6650);
DOT 1 (-4800 5650);
DOT 1 (-4700 5150);
DOT 1 (-4750 5150);
DOT 1 (-4750 5050);
DOT 1 (-4800 5050);
DOT 1 (-5000 6650);
DOT 1 (-6100 6750);
DOT 1 (-6100 6150);
DOT 1 (-6100 5750);
DOT 1 (-6100 5150);
DOT 1 (-4800 6050);
DOT 1 (-5000 5050);
FORCENOTE
FPGA 4/5
(-8800 9950) 0;
DISPLAY LEFT (-8800 9950);
DISPLAY 3.936170 (-8800 9950);
FORCENOTE
LVDS_25 OUTPUT
(-4200 6100) 0;
DISPLAY LEFT (-4200 6100);
DISPLAY 1.276596 (-4200 6100);
FORCENOTE
VCCIO = 2.5V.
(-9700 8600) 0;
DISPLAY LEFT (-9700 8600);
DISPLAY 3.936170 (-9700 8600);
FORCENOTE
RSVD EXTERNAL R TERM. PLACE R CLOSE TO FPGA'S PIN
(-5950 7350) 0;
DISPLAY LEFT (-5950 7350);
DISPLAY 1.276596 (-5950 7350);
FORCENOTE
LVDS_25 OUTPUT
(-4200 5700) 0;
DISPLAY LEFT (-4200 5700);
DISPLAY 1.276596 (-4200 5700);
QUIT
